FILE_TYPE = MACRO_DRAWING;
SET COLOR_WIRE YELLOW;
SET COLOR_PROP MONO;
SET COLOR_DOT WHITE;
SET COLOR_ARC YELLOW;
SET COLOR_BODY GREEN;
SET COLOR_NOTE MONO;
SET PROP_DISPLAY VALUE;
SET PAGE_NUMBER P161;
FORCEADD CONN6_C74770005..1
(-725 3775);
FORCEPROP 2 LASTPIN (-825 3775) $PN 4
J 2
(-835 3785);
DISPLAY 0.617021 (-835 3785);
PAINT ORANGE (-835 3785);
FORCEPROP 2 LASTPIN (-825 3725) $PN 5
J 2
(-835 3735);
DISPLAY 0.617021 (-835 3735);
PAINT ORANGE (-835 3735);
FORCEPROP 2 LASTPIN (-825 3675) $PN 6
J 2
(-835 3685);
DISPLAY 0.617021 (-835 3685);
PAINT ORANGE (-835 3685);
FORCEPROP 2 LASTPIN (-825 3825) $PN 3
J 2
(-835 3835);
DISPLAY 0.617021 (-835 3835);
PAINT ORANGE (-835 3835);
FORCEPROP 2 LASTPIN (-825 3875) $PN 2
J 2
(-835 3885);
DISPLAY 0.617021 (-835 3885);
PAINT ORANGE (-835 3885);
FORCEPROP 2 LASTPIN (-825 3925) $PN 1
J 2
(-835 3935);
DISPLAY 0.617021 (-835 3935);
PAINT ORANGE (-835 3935);
FORCEPROP 1 LAST MATERIAL HDR
J 0
(-775 4050);
DISPLAY 0.617021 (-775 4050);
PAINT SKYBLUE (-775 4050);
FORCEPROP 1 LAST PART_NUMBER C74770-005
J 0
(-775 3500);
DISPLAY 0.617021 (-775 3500);
PAINT BLUE (-775 3500);
FORCEPROP 1 LAST LOCATION J1F2
J 0
(-850 4100);
DISPLAY 0.617021 (-850 4100);
PAINT AQUA (-850 4100);
FORCEPROP 2 LAST CDS_LIB mstr_conn
J 0
(-725 3775);
PAINT ORANGE (-725 3775);
DISPLAY INVISIBLE (-725 3775);
FORCEPROP 1 LAST PATH I1
J 0
(-325 4050);
DISPLAY 0.978723 (-325 4050);
PAINT BLUE (-325 4050);
DISPLAY INVISIBLE (-325 4050);
FORCEPROP 0 LAST ROOM CPU_FANS
J 0
(-850 4150);
DISPLAY 1.021277 (-850 4150);
PAINT ORANGE (-850 4150);
DISPLAY INVISIBLE (-850 4150);
FORCEPROP 2 LAST CDS_LOCATION J1F2
J 0
(-850 4100);
DISPLAY 0.617021 (-850 4100);
PAINT AQUA (-850 4100);
DISPLAY INVISIBLE (-850 4100);
FORCEPROP 2 LAST SEC 1
J 0
(-850 4150);
DISPLAY 0.680851 (-850 4150);
PAINT MONO (-850 4150);
DISPLAY INVISIBLE (-850 4150);
FORCEPROP 0 LAST BOM_COST SM_THERM
J 0
(-850 4200);
DISPLAY 1.021277 (-850 4200);
PAINT ORANGE (-850 4200);
DISPLAY INVISIBLE (-850 4200);
FORCEPROP 2 LAST SEC_TYPE PIP
J 0
(-850 4150);
DISPLAY 1.021277 (-850 4150);
PAINT ORANGE (-850 4150);
DISPLAY INVISIBLE (-850 4150);
FORCEPROP 0 LAST VOLTAGE 16V
J 0
(-850 4150);
DISPLAY 0.617021 (-850 4150);
PAINT SKYBLUE (-850 4150);
DISPLAY INVISIBLE (-850 4150);
FORCEPROP 1 LAST PACK_TYPE PIP
J 0
(-775 4150);
DISPLAY 0.978723 (-775 4150);
PAINT SKYBLUE (-775 4150);
DISPLAY INVISIBLE (-775 4150);
FORCEPROP 0 LAST TOLERANCE 10%
J 0
(-850 4250);
DISPLAY 0.617021 (-850 4250);
PAINT SKYBLUE (-850 4250);
DISPLAY INVISIBLE (-850 4250);
FORCEPROP 0 LAST VALUE 0.22UF
J 0
(-850 4200);
DISPLAY 0.617021 (-850 4200);
PAINT SKYBLUE (-850 4200);
DISPLAY INVISIBLE (-850 4200);
FORCEADD OFFPAGE..1
(-7375 1100);
FORCEPROP 2 LAST $XR0 120 
J 0
(-7627 1100);
DISPLAY 0.638298 (-7627 1100);
PAINT MONO (-7627 1100);
FORCEPROP 2 LAST $XR1 147 
J 0
(-7747 1100);
DISPLAY 0.638298 (-7747 1100);
PAINT MONO (-7747 1100);
FORCEPROP 1 LAST COMMENT_BODY TRUE
J 0
(-7250 1000);
DISPLAY 1.170213 (-7250 1000);
PAINT PEACH (-7250 1000);
DISPLAY INVISIBLE (-7250 1000);
FORCEPROP 2 LAST PATH I100
J 0
(-7325 1175);
DISPLAY 1.021277 (-7325 1175);
PAINT ORANGE (-7325 1175);
DISPLAY INVISIBLE (-7325 1175);
FORCEPROP 2 LAST CDS_LIB mstr_standard
J 0
(-7375 1100);
PAINT ORANGE (-7375 1100);
DISPLAY INVISIBLE (-7375 1100);
FORCEPROP 1 LAST OFFPAGE TRUE
J 0
(-7050 975);
DISPLAY 1.170213 (-7050 975);
PAINT GREEN (-7050 975);
DISPLAY INVISIBLE (-7050 975);
FORCEADD RES..1
(-5600 1100);
FORCEPROP 1 LAST WATTAGE 1/16W
J 2
(-5625 950);
DISPLAY 0.617021 (-5625 950);
PAINT SKYBLUE (-5625 950);
FORCEPROP 1 LAST MATERIAL CHIP
J 0
(-5600 950);
DISPLAY 0.617021 (-5600 950);
PAINT SKYBLUE (-5600 950);
FORCEPROP 1 LAST PACK_TYPE 0402
J 0
(-5350 950);
DISPLAY 0.617021 (-5350 950);
PAINT SKYBLUE (-5350 950);
FORCEPROP 1 LAST TOLERANCE 1.0%
J 0
(-5600 1000);
DISPLAY 0.617021 (-5600 1000);
PAINT SKYBLUE (-5600 1000);
FORCEPROP 1 LAST VALUE 221
J 2
(-5625 1000);
DISPLAY 0.617021 (-5625 1000);
PAINT SKYBLUE (-5625 1000);
FORCEPROP 1 LASTPIN (-5700 1100) $PN 1
J 0
(-5688 1112);
DISPLAY 0.617021 (-5688 1112);
PAINT ORANGE (-5688 1112);
FORCEPROP 1 LAST PART_NUMBER G21796-271
J 0
(-5650 1200);
DISPLAY 0.617021 (-5650 1200);
PAINT BLUE (-5650 1200);
FORCEPROP 1 LAST LOCATION R2U44
J 0
(-5650 1150);
DISPLAY 0.617021 (-5650 1150);
PAINT AQUA (-5650 1150);
FORCEPROP 1 LASTPIN (-5500 1100) $PN 2
J 0
(-5538 1112);
DISPLAY 0.617021 (-5538 1112);
PAINT ORANGE (-5538 1112);
FORCEPROP 0 LAST ROOM CPU_FANS
J 0
(-5650 1300);
DISPLAY 1.021277 (-5650 1300);
PAINT ORANGE (-5650 1300);
DISPLAY INVISIBLE (-5650 1300);
FORCEPROP 1 LAST PATH I102
J 0
(-5650 1250);
DISPLAY 0.978723 (-5650 1250);
PAINT WHITE (-5650 1250);
DISPLAY INVISIBLE (-5650 1250);
FORCEPROP 2 LAST CDS_LOCATION R2U44
J 0
(-5650 1150);
DISPLAY 0.617021 (-5650 1150);
PAINT AQUA (-5650 1150);
DISPLAY INVISIBLE (-5650 1150);
FORCEPROP 2 LAST SEC 1
J 0
(-5650 1300);
DISPLAY 0.680851 (-5650 1300);
PAINT MONO (-5650 1300);
DISPLAY INVISIBLE (-5650 1300);
FORCEPROP 2 LAST SEC_TYPE 0402
J 0
(-5650 1300);
DISPLAY 1.021277 (-5650 1300);
PAINT ORANGE (-5650 1300);
DISPLAY INVISIBLE (-5650 1300);
FORCEPROP 0 LAST BOM_COST SM_THERM
J 0
(-5650 1400);
DISPLAY 1.021277 (-5650 1400);
PAINT ORANGE (-5650 1400);
DISPLAY INVISIBLE (-5650 1400);
FORCEPROP 2 LAST CDS_LIB mstr_discrete
J 0
(-5600 1100);
PAINT ORANGE (-5600 1100);
DISPLAY INVISIBLE (-5600 1100);
FORCEADD OFFPAGE..2
(-4900 1100);
FORCEPROP 2 LAST $XR0 161 
J 0
(-4711 1100);
DISPLAY 0.638298 (-4711 1100);
PAINT MONO (-4711 1100);
FORCEPROP 1 LAST OFFPAGE TRUE
J 0
(-4575 975);
DISPLAY 0.872340 (-4575 975);
PAINT GREEN (-4575 975);
DISPLAY INVISIBLE (-4575 975);
FORCEPROP 1 LAST COMMENT_BODY TRUE
J 0
(-4945 1005);
DISPLAY 0.872340 (-4945 1005);
PAINT GREEN (-4945 1005);
DISPLAY INVISIBLE (-4945 1005);
FORCEPROP 2 LAST CDS_LIB mstr_standard
J 0
(-4900 1100);
PAINT ORANGE (-4900 1100);
DISPLAY INVISIBLE (-4900 1100);
FORCEPROP 2 LAST PATH I103
J 0
(-4700 1150);
DISPLAY 1.021277 (-4700 1150);
PAINT ORANGE (-4700 1150);
DISPLAY INVISIBLE (-4700 1150);
FORCEADD GND..1
R 2
(-6200 475);
FORCEPROP 3 LASTPIN (-6200 525) SIG_NAME GND\g
J 0
(-6190 535);
DISPLAY 0.659574 (-6190 535);
PAINT MONO (-6190 535);
DISPLAY INVISIBLE (-6190 535);
FORCEPROP 1 LAST PATH I104
J 2
(-6275 475);
DISPLAY 0.872340 (-6275 475);
PAINT AQUA (-6275 475);
DISPLAY INVISIBLE (-6275 475);
FORCEPROP 1 LAST BODY_TYPE PLUMBING
J 2
(-6155 432);
DISPLAY 0.340426 (-6155 432);
PAINT GREEN (-6155 432);
DISPLAY INVISIBLE (-6155 432);
FORCEPROP 1 LAST VOLTAGE 0.0V
J 2
(-6155 432);
DISPLAY 0.340426 (-6155 432);
PAINT SKYBLUE (-6155 432);
DISPLAY INVISIBLE (-6155 432);
FORCEPROP 1 LAST SIZE 1B
J 2
(-6275 425);
DISPLAY 2.446809 (-6275 425);
PAINT ORANGE (-6275 425);
DISPLAY INVISIBLE (-6275 425);
FORCEPROP 2 LAST CDS_LIB mstr_symbols
J 0
(-6200 475);
PAINT ORANGE (-6200 475);
DISPLAY INVISIBLE (-6200 475);
FORCEPROP 2 LAST ROOM PLD
J 0
(-6400 555);
DISPLAY 1.595745 (-6400 555);
PAINT WHITE (-6400 555);
DISPLAY INVISIBLE (-6400 555);
FORCEPROP 1 LAST HDL_POWER GND
J 2
(-6200 625);
PAINT GREEN (-6200 625);
DISPLAY INVISIBLE (-6200 625);
FORCEADD P3V3_STBY..1
(-6200 850);
FORCEPROP 3 LASTPIN (-6200 800) SIG_NAME P3V3_STBY\g
J 0
(-6190 810);
DISPLAY 0.659574 (-6190 810);
PAINT MONO (-6190 810);
DISPLAY INVISIBLE (-6190 810);
FORCEPROP 1 LAST HDL_POWER P3V3_STBY
J 0
(-6500 725);
DISPLAY 0.872340 (-6500 725);
PAINT ORANGE (-6500 725);
DISPLAY INVISIBLE (-6500 725);
FORCEPROP 1 LAST VOLTAGE 3.3V
J 0
(-6245 807);
DISPLAY 0.340426 (-6245 807);
PAINT SKYBLUE (-6245 807);
DISPLAY INVISIBLE (-6245 807);
FORCEPROP 1 LAST BODY_TYPE PLUMBING
J 0
(-6245 807);
DISPLAY 0.340426 (-6245 807);
PAINT GREEN (-6245 807);
DISPLAY INVISIBLE (-6245 807);
FORCEPROP 2 LAST CDS_LIB mstr_symbols
J 0
(-6200 850);
PAINT ORANGE (-6200 850);
DISPLAY INVISIBLE (-6200 850);
FORCEPROP 1 LAST SIZE 1B
J 0
(-6155 872);
DISPLAY 0.340426 (-6155 872);
PAINT GREEN (-6155 872);
DISPLAY INVISIBLE (-6155 872);
FORCEPROP 1 LAST PATH I105
J 0
(-6155 852);
DISPLAY 0.340426 (-6155 852);
PAINT GREEN (-6155 852);
DISPLAY INVISIBLE (-6155 852);
FORCEADD P12V_FAN..1
(-1375 2575);
FORCEPROP 3 LASTPIN (-1375 2525) SIG_NAME P12V_FAN\g
J 0
(-1365 2535);
DISPLAY 0.659574 (-1365 2535);
PAINT MONO (-1365 2535);
DISPLAY INVISIBLE (-1365 2535);
FORCEPROP 1 LAST BODY_TYPE PLUMBING
J 0
(-1420 2532);
DISPLAY 0.340426 (-1420 2532);
PAINT GREEN (-1420 2532);
DISPLAY INVISIBLE (-1420 2532);
FORCEPROP 1 LAST VOLTAGE 12.0V
J 0
(-1420 2532);
DISPLAY 0.340426 (-1420 2532);
PAINT SKYBLUE (-1420 2532);
DISPLAY INVISIBLE (-1420 2532);
FORCEPROP 1 LAST HDL_POWER P12V_FAN
J 1
(-1375 2625);
DISPLAY 0.872340 (-1375 2625);
PAINT GREEN (-1375 2625);
DISPLAY INVISIBLE (-1375 2625);
FORCEPROP 1 LAST PATH I108
J 0
(-1325 2600);
DISPLAY 0.872340 (-1325 2600);
PAINT AQUA (-1325 2600);
DISPLAY INVISIBLE (-1325 2600);
FORCEPROP 2 LAST CDS_LIB mstr_symbols
J 0
(-1375 2575);
PAINT ORANGE (-1375 2575);
DISPLAY INVISIBLE (-1375 2575);
FORCEADD P12V_FAN..1
(-1500 4725);
FORCEPROP 3 LASTPIN (-1500 4675) SIG_NAME P12V_FAN\g
J 0
(-1490 4685);
DISPLAY 0.659574 (-1490 4685);
PAINT MONO (-1490 4685);
DISPLAY INVISIBLE (-1490 4685);
FORCEPROP 1 LAST BODY_TYPE PLUMBING
J 0
(-1545 4682);
DISPLAY 0.340426 (-1545 4682);
PAINT GREEN (-1545 4682);
DISPLAY INVISIBLE (-1545 4682);
FORCEPROP 1 LAST VOLTAGE 12.0V
J 0
(-1545 4682);
DISPLAY 0.340426 (-1545 4682);
PAINT SKYBLUE (-1545 4682);
DISPLAY INVISIBLE (-1545 4682);
FORCEPROP 1 LAST HDL_POWER P12V_FAN
J 1
(-1500 4775);
DISPLAY 0.872340 (-1500 4775);
PAINT GREEN (-1500 4775);
DISPLAY INVISIBLE (-1500 4775);
FORCEPROP 1 LAST PATH I110
J 0
(-1450 4750);
DISPLAY 0.872340 (-1450 4750);
PAINT AQUA (-1450 4750);
DISPLAY INVISIBLE (-1450 4750);
FORCEPROP 2 LAST CDS_LIB mstr_symbols
J 0
(-1500 4725);
PAINT ORANGE (-1500 4725);
DISPLAY INVISIBLE (-1500 4725);
FORCEADD GND..1
R 5
(-1200 1850);
FORCEPROP 3 LASTPIN (-1150 1850) SIG_NAME GND\g
J 0
(-1140 1860);
DISPLAY 0.659574 (-1140 1860);
PAINT MONO (-1140 1860);
DISPLAY INVISIBLE (-1140 1860);
FORCEPROP 1 LAST PATH I111
R 3
J 0
(-1200 1775);
DISPLAY 0.872340 (-1200 1775);
PAINT AQUA (-1200 1775);
DISPLAY INVISIBLE (-1200 1775);
FORCEPROP 1 LAST BODY_TYPE PLUMBING
R 3
J 0
(-1243 1895);
DISPLAY 0.340426 (-1243 1895);
PAINT GREEN (-1243 1895);
DISPLAY INVISIBLE (-1243 1895);
FORCEPROP 1 LAST SIZE 1B
R 3
J 0
(-1250 1775);
DISPLAY 1.170213 (-1250 1775);
PAINT AQUA (-1250 1775);
DISPLAY INVISIBLE (-1250 1775);
FORCEPROP 2 LAST CDS_LIB mstr_symbols
R 3
J 0
(-1200 1850);
PAINT ORANGE (-1200 1850);
DISPLAY INVISIBLE (-1200 1850);
FORCEPROP 1 LAST VOLTAGE 0.0V
R 3
J 0
(-1243 1895);
DISPLAY 0.340426 (-1243 1895);
PAINT SKYBLUE (-1243 1895);
DISPLAY INVISIBLE (-1243 1895);
FORCEPROP 1 LAST HDL_POWER GND
R 3
J 0
(-1050 1850);
DISPLAY 1.170213 (-1050 1850);
PAINT GREEN (-1050 1850);
DISPLAY INVISIBLE (-1050 1850);
FORCEADD CAP_A..1
(-5775 2150);
FORCEPROP 1 LAST PACK_TYPE 0402V
J 0
(-5725 1950);
DISPLAY 0.617021 (-5725 1950);
PAINT SKYBLUE (-5725 1950);
FORCEPROP 1 LAST PART_NUMBER A36096-030
J 0
(-5725 2000);
DISPLAY 0.617021 (-5725 2000);
PAINT BLUE (-5725 2000);
FORCEPROP 1 LASTPIN (-5775 2050) $PN 2
J 0
(-5765 2030);
DISPLAY 0.617021 (-5765 2030);
PAINT ORANGE (-5765 2030);
FORCEPROP 1 LASTPIN (-5775 2250) $PN 1
J 0
(-5765 2230);
DISPLAY 0.617021 (-5765 2230);
PAINT ORANGE (-5765 2230);
FORCEPROP 1 LAST TOLERANCE 10%
J 0
(-5725 2100);
DISPLAY 0.617021 (-5725 2100);
PAINT SKYBLUE (-5725 2100);
FORCEPROP 1 LAST VOLTAGE 16V
J 0
(-5725 2150);
DISPLAY 0.617021 (-5725 2150);
PAINT SKYBLUE (-5725 2150);
FORCEPROP 1 LAST MATERIAL X7R
J 0
(-5725 2050);
DISPLAY 0.617021 (-5725 2050);
PAINT SKYBLUE (-5725 2050);
FORCEPROP 1 LAST VALUE 0.1UF
J 0
(-5725 2200);
DISPLAY 0.617021 (-5725 2200);
PAINT SKYBLUE (-5725 2200);
FORCEPROP 1 LAST LOCATION C1E22
J 0
(-5725 2250);
DISPLAY 0.617021 (-5725 2250);
PAINT AQUA (-5725 2250);
FORCEPROP 2 LAST CDS_LIB dev_discrete
J 0
(-5775 2150);
PAINT ORANGE (-5775 2150);
DISPLAY INVISIBLE (-5775 2150);
FORCEPROP 2 LAST CDS_LOCATION C1E22
J 0
(-5725 2250);
DISPLAY 0.617021 (-5725 2250);
PAINT AQUA (-5725 2250);
DISPLAY INVISIBLE (-5725 2250);
FORCEPROP 2 LAST CDS_SEC 1
J 0
(-5725 2300);
PAINT ORANGE (-5725 2300);
DISPLAY INVISIBLE (-5725 2300);
FORCEPROP 2 LAST ROOM CPUFANS
J 0
(-5725 2300);
DISPLAY 1.021277 (-5725 2300);
PAINT ORANGE (-5725 2300);
DISPLAY INVISIBLE (-5725 2300);
FORCEPROP 1 LAST PATH I113
J 0
(-5725 2300);
DISPLAY 0.978723 (-5725 2300);
PAINT WHITE (-5725 2300);
DISPLAY INVISIBLE (-5725 2300);
FORCEPROP 2 LAST SEC 1
J 0
(-5725 2350);
DISPLAY 0.680851 (-5725 2350);
PAINT MONO (-5725 2350);
DISPLAY INVISIBLE (-5725 2350);
FORCEPROP 2 LAST SEC_TYPE 0402V
J 0
(-5725 2350);
DISPLAY 1.021277 (-5725 2350);
PAINT ORANGE (-5725 2350);
DISPLAY INVISIBLE (-5725 2350);
FORCEPROP 2 LAST BOM_COST SM_THERM
J 0
(-5725 2350);
DISPLAY 1.021277 (-5725 2350);
PAINT ORANGE (-5725 2350);
DISPLAY INVISIBLE (-5725 2350);
FORCEADD OFFPAGE..2
(-5300 2575);
FORCEPROP 2 LAST $XR0 181 
J 0
(-5111 2575);
DISPLAY 0.638298 (-5111 2575);
PAINT MONO (-5111 2575);
FORCEPROP 2 LAST $XR1 198 
J 0
(-4991 2575);
DISPLAY 0.638298 (-4991 2575);
PAINT MONO (-4991 2575);
FORCEPROP 1 LAST COMMENT_BODY TRUE
J 0
(-5345 2480);
DISPLAY 0.872340 (-5345 2480);
PAINT GREEN (-5345 2480);
DISPLAY INVISIBLE (-5345 2480);
FORCEPROP 2 LAST PATH I114
J 0
(-5125 2650);
DISPLAY 1.021277 (-5125 2650);
PAINT ORANGE (-5125 2650);
DISPLAY INVISIBLE (-5125 2650);
FORCEPROP 2 LAST CDS_LIB mstr_standard
J 0
(-5300 2575);
PAINT ORANGE (-5300 2575);
DISPLAY INVISIBLE (-5300 2575);
FORCEPROP 1 LAST OFFPAGE TRUE
J 0
(-4975 2450);
DISPLAY 0.872340 (-4975 2450);
PAINT GREEN (-4975 2450);
DISPLAY INVISIBLE (-4975 2450);
FORCEADD OFFPAGE..1
(-7150 2625);
FORCEPROP 2 LAST $XR0 181 
J 0
(-7402 2625);
DISPLAY 0.638298 (-7402 2625);
PAINT MONO (-7402 2625);
FORCEPROP 2 LAST $XR1 191 
J 0
(-7522 2625);
DISPLAY 0.638298 (-7522 2625);
PAINT MONO (-7522 2625);
FORCEPROP 2 LAST $XR2 198 
J 0
(-7642 2625);
DISPLAY 0.638298 (-7642 2625);
PAINT MONO (-7642 2625);
FORCEPROP 1 LAST OFFPAGE TRUE
J 0
(-6825 2500);
DISPLAY 1.170213 (-6825 2500);
PAINT GREEN (-6825 2500);
DISPLAY INVISIBLE (-6825 2500);
FORCEPROP 1 LAST COMMENT_BODY TRUE
J 0
(-7025 2525);
DISPLAY 1.170213 (-7025 2525);
PAINT PEACH (-7025 2525);
DISPLAY INVISIBLE (-7025 2525);
FORCEPROP 2 LAST CDS_LIB mstr_standard
J 0
(-7150 2625);
PAINT ORANGE (-7150 2625);
DISPLAY INVISIBLE (-7150 2625);
FORCEPROP 2 LAST PATH I115
J 0
(-7100 2700);
DISPLAY 1.021277 (-7100 2700);
PAINT ORANGE (-7100 2700);
DISPLAY INVISIBLE (-7100 2700);
FORCEADD OFFPAGE..1
(-7150 2525);
FORCEPROP 2 LAST $XR0 200 
J 0
(-7402 2525);
DISPLAY 0.638298 (-7402 2525);
PAINT MONO (-7402 2525);
FORCEPROP 1 LAST OFFPAGE TRUE
J 0
(-6825 2400);
DISPLAY 1.170213 (-6825 2400);
PAINT GREEN (-6825 2400);
DISPLAY INVISIBLE (-6825 2400);
FORCEPROP 1 LAST COMMENT_BODY TRUE
J 0
(-7025 2425);
DISPLAY 1.170213 (-7025 2425);
PAINT PEACH (-7025 2425);
DISPLAY INVISIBLE (-7025 2425);
FORCEPROP 2 LAST CDS_LIB mstr_standard
J 0
(-7150 2525);
PAINT ORANGE (-7150 2525);
DISPLAY INVISIBLE (-7150 2525);
FORCEPROP 2 LAST PATH I116
J 0
(-7100 2600);
DISPLAY 1.021277 (-7100 2600);
PAINT ORANGE (-7100 2600);
DISPLAY INVISIBLE (-7100 2600);
FORCEADD P3V3_STBY..1
(-5775 2350);
FORCEPROP 3 LASTPIN (-5775 2300) SIG_NAME P3V3_STBY\g
J 0
(-5765 2310);
DISPLAY 0.659574 (-5765 2310);
PAINT MONO (-5765 2310);
DISPLAY INVISIBLE (-5765 2310);
FORCEPROP 1 LAST HDL_POWER P3V3_STBY
J 0
(-6075 2225);
DISPLAY 0.872340 (-6075 2225);
PAINT ORANGE (-6075 2225);
DISPLAY INVISIBLE (-6075 2225);
FORCEPROP 1 LAST SIZE 1B
J 0
(-5730 2372);
DISPLAY 0.340426 (-5730 2372);
PAINT GREEN (-5730 2372);
DISPLAY INVISIBLE (-5730 2372);
FORCEPROP 2 LAST CDS_LIB mstr_symbols
J 0
(-5775 2350);
PAINT ORANGE (-5775 2350);
DISPLAY INVISIBLE (-5775 2350);
FORCEPROP 1 LAST PATH I117
J 0
(-5730 2352);
DISPLAY 0.340426 (-5730 2352);
PAINT GREEN (-5730 2352);
DISPLAY INVISIBLE (-5730 2352);
FORCEPROP 1 LAST VOLTAGE 3.3V
J 0
(-5820 2307);
DISPLAY 0.340426 (-5820 2307);
PAINT SKYBLUE (-5820 2307);
DISPLAY INVISIBLE (-5820 2307);
FORCEPROP 1 LAST BODY_TYPE PLUMBING
J 0
(-5820 2307);
DISPLAY 0.340426 (-5820 2307);
PAINT GREEN (-5820 2307);
DISPLAY INVISIBLE (-5820 2307);
FORCEADD GND..1
(-5775 1950);
FORCEPROP 3 LASTPIN (-5775 2000) SIG_NAME GND\g
J 0
(-5765 2010);
DISPLAY 0.659574 (-5765 2010);
PAINT MONO (-5765 2010);
DISPLAY INVISIBLE (-5765 2010);
FORCEPROP 1 LAST VOLTAGE 0.0V
J 0
(-5820 1907);
DISPLAY 0.340426 (-5820 1907);
PAINT SKYBLUE (-5820 1907);
DISPLAY INVISIBLE (-5820 1907);
FORCEPROP 2 LAST CDS_LIB mstr_symbols
J 0
(-5775 1950);
PAINT ORANGE (-5775 1950);
DISPLAY INVISIBLE (-5775 1950);
FORCEPROP 1 LAST SIZE 1B
J 0
(-5700 1900);
DISPLAY 1.170213 (-5700 1900);
PAINT AQUA (-5700 1900);
DISPLAY INVISIBLE (-5700 1900);
FORCEPROP 1 LAST BODY_TYPE PLUMBING
J 0
(-5820 1907);
DISPLAY 0.340426 (-5820 1907);
PAINT GREEN (-5820 1907);
DISPLAY INVISIBLE (-5820 1907);
FORCEPROP 1 LAST PATH I118
J 0
(-5700 1950);
DISPLAY 0.872340 (-5700 1950);
PAINT AQUA (-5700 1950);
DISPLAY INVISIBLE (-5700 1950);
FORCEPROP 1 LAST HDL_POWER GND
J 0
(-5775 2100);
DISPLAY 1.170213 (-5775 2100);
PAINT GREEN (-5775 2100);
DISPLAY INVISIBLE (-5775 2100);
FORCEADD P3V3_STBY..1
(-5950 3025);
FORCEPROP 3 LASTPIN (-5950 2975) SIG_NAME P3V3_STBY\g
J 0
(-5940 2985);
DISPLAY 0.659574 (-5940 2985);
PAINT MONO (-5940 2985);
DISPLAY INVISIBLE (-5940 2985);
FORCEPROP 1 LAST HDL_POWER P3V3_STBY
J 0
(-6250 2900);
DISPLAY 0.872340 (-6250 2900);
PAINT ORANGE (-6250 2900);
DISPLAY INVISIBLE (-6250 2900);
FORCEPROP 1 LAST PATH I119
J 0
(-5905 3027);
DISPLAY 0.340426 (-5905 3027);
PAINT GREEN (-5905 3027);
DISPLAY INVISIBLE (-5905 3027);
FORCEPROP 1 LAST BODY_TYPE PLUMBING
J 0
(-5995 2982);
DISPLAY 0.340426 (-5995 2982);
PAINT GREEN (-5995 2982);
DISPLAY INVISIBLE (-5995 2982);
FORCEPROP 1 LAST SIZE 1B
J 0
(-5905 3047);
DISPLAY 0.340426 (-5905 3047);
PAINT GREEN (-5905 3047);
DISPLAY INVISIBLE (-5905 3047);
FORCEPROP 2 LAST CDS_LIB mstr_symbols
J 0
(-5950 3025);
PAINT ORANGE (-5950 3025);
DISPLAY INVISIBLE (-5950 3025);
FORCEPROP 1 LAST VOLTAGE 3.3V
J 0
(-5995 2982);
DISPLAY 0.340426 (-5995 2982);
PAINT SKYBLUE (-5995 2982);
DISPLAY INVISIBLE (-5995 2982);
FORCEADD RES..2
(-5950 2800);
FORCEPROP 1 LASTPIN (-5950 2700) $PN 2
J 0
(-5945 2710);
DISPLAY 0.617021 (-5945 2710);
PAINT ORANGE (-5945 2710);
FORCEPROP 1 LASTPIN (-5950 2900) $PN 1
J 0
(-5945 2862);
DISPLAY 0.617021 (-5945 2862);
PAINT ORANGE (-5945 2862);
FORCEPROP 1 LAST WATTAGE 1/16W
J 0
(-5910 2775);
DISPLAY 0.617021 (-5910 2775);
PAINT SKYBLUE (-5910 2775);
FORCEPROP 1 LAST PACK_TYPE 0402
J 0
(-5910 2625);
DISPLAY 0.617021 (-5910 2625);
PAINT SKYBLUE (-5910 2625);
FORCEPROP 1 LAST TOLERANCE 1%
J 0
(-5905 2825);
DISPLAY 0.617021 (-5905 2825);
PAINT SKYBLUE (-5905 2825);
FORCEPROP 1 LAST VALUE 10.0K
J 0
(-5905 2875);
DISPLAY 0.617021 (-5905 2875);
PAINT SKYBLUE (-5905 2875);
FORCEPROP 1 LAST LOCATION R1E11
J 0
(-5905 2925);
DISPLAY 0.617021 (-5905 2925);
PAINT AQUA (-5905 2925);
FORCEPROP 1 LAST MATERIAL EMPTY
J 0
(-5910 2725);
DISPLAY 0.617021 (-5910 2725);
PAINT RED (-5910 2725);
FORCEPROP 1 LAST PART_NUMBER G21796-016
J 0
(-5910 2675);
DISPLAY 0.617021 (-5910 2675);
PAINT BLUE (-5910 2675);
FORCEPROP 2 LAST CDS_LIB mstr_discrete
J 0
(-5950 2800);
PAINT ORANGE (-5950 2800);
DISPLAY INVISIBLE (-5950 2800);
FORCEPROP 2 LAST CDS_LOCATION R1E11
J 0
(-5905 2925);
DISPLAY 0.617021 (-5905 2925);
PAINT AQUA (-5905 2925);
DISPLAY INVISIBLE (-5905 2925);
FORCEPROP 0 LAST ROOM CPU_FANS
J 0
(-5900 3025);
DISPLAY 1.021277 (-5900 3025);
PAINT ORANGE (-5900 3025);
DISPLAY INVISIBLE (-5900 3025);
FORCEPROP 1 LAST PATH I120
J 0
(-5900 2975);
DISPLAY 0.978723 (-5900 2975);
PAINT WHITE (-5900 2975);
DISPLAY INVISIBLE (-5900 2975);
FORCEPROP 2 LAST SEC 1
J 0
(-5900 3025);
DISPLAY 0.680851 (-5900 3025);
PAINT MONO (-5900 3025);
DISPLAY INVISIBLE (-5900 3025);
FORCEPROP 2 LAST SEC_TYPE 0402
J 0
(-5900 3025);
DISPLAY 1.021277 (-5900 3025);
PAINT ORANGE (-5900 3025);
DISPLAY INVISIBLE (-5900 3025);
FORCEPROP 0 LAST BOM_COST SM_THERM
J 0
(-5900 3125);
DISPLAY 1.021277 (-5900 3125);
PAINT ORANGE (-5900 3125);
DISPLAY INVISIBLE (-5900 3125);
FORCEADD TTL1G08..1
(-6250 2575);
FORCEPROP 1 LAST VALUE NC7SZ08
J 1
(-6250 2450);
DISPLAY 0.617021 (-6250 2450);
PAINT SKYBLUE (-6250 2450);
FORCEPROP 2 LASTPIN (-6400 2525) $PN 2
J 2
(-6410 2535);
DISPLAY 0.617021 (-6410 2535);
PAINT ORANGE (-6410 2535);
FORCEPROP 2 LASTPIN (-6400 2625) $PN 1
J 2
(-6410 2635);
DISPLAY 0.617021 (-6410 2635);
PAINT ORANGE (-6410 2635);
FORCEPROP 1 LAST MATERIAL IC
J 1
(-6275 2785);
DISPLAY 0.617021 (-6275 2785);
PAINT SKYBLUE (-6275 2785);
FORCEPROP 1 LAST PACK_TYPE SOTLF
J 1
(-6275 2750);
DISPLAY 0.617021 (-6275 2750);
PAINT SKYBLUE (-6275 2750);
FORCEPROP 1 LAST LOCATION U1E2
J 1
(-6275 2710);
DISPLAY 0.617021 (-6275 2710);
PAINT AQUA (-6275 2710);
FORCEPROP 1 LAST PART_NUMBER D10321-001
J 1
(-6275 2675);
DISPLAY 0.617021 (-6275 2675);
PAINT BLUE (-6275 2675);
FORCEPROP 1 LAST POWER_GROUP VCC=P3V3_STBY;GND=GND;
J 1
(-6225 2400);
DISPLAY 0.617021 (-6225 2400);
PAINT ORANGE (-6225 2400);
FORCEPROP 2 LASTPIN (-6100 2575) $PN 4
J 0
(-6090 2585);
DISPLAY 0.617021 (-6090 2585);
PAINT ORANGE (-6090 2585);
FORCEPROP 2 LAST CDS_LOCATION U1E2
J 1
(-6275 2710);
DISPLAY 0.617021 (-6275 2710);
PAINT AQUA (-6275 2710);
DISPLAY INVISIBLE (-6275 2710);
FORCEPROP 2 LAST CDS_LIB mstr_ttl
J 0
(-6250 2575);
PAINT ORANGE (-6250 2575);
DISPLAY INVISIBLE (-6250 2575);
FORCEPROP 0 LAST ROOM CPU_FANS
J 0
(-6275 2875);
DISPLAY 1.021277 (-6275 2875);
PAINT ORANGE (-6275 2875);
DISPLAY INVISIBLE (-6275 2875);
FORCEPROP 1 LAST PATH I121
J 1
(-6270 2840);
DISPLAY 0.702128 (-6270 2840);
PAINT WHITE (-6270 2840);
DISPLAY INVISIBLE (-6270 2840);
FORCEPROP 2 LAST SEC_TYPE SOTLF
J 0
(-6250 2875);
DISPLAY 1.021277 (-6250 2875);
PAINT ORANGE (-6250 2875);
DISPLAY INVISIBLE (-6250 2875);
FORCEPROP 2 LAST SEC 1
J 0
(-6250 2875);
DISPLAY 0.680851 (-6250 2875);
PAINT MONO (-6250 2875);
DISPLAY INVISIBLE (-6250 2875);
FORCEPROP 0 LAST BOM_COST SM_THERM
J 0
(-6275 2875);
DISPLAY 1.021277 (-6275 2875);
PAINT ORANGE (-6275 2875);
DISPLAY INVISIBLE (-6275 2875);
FORCEADD GND..1
R 5
(-1125 3925);
FORCEPROP 3 LASTPIN (-1075 3925) SIG_NAME GND\g
J 0
(-1065 3935);
DISPLAY 0.659574 (-1065 3935);
PAINT MONO (-1065 3935);
DISPLAY INVISIBLE (-1065 3935);
FORCEPROP 1 LAST VOLTAGE 0.0V
R 3
J 0
(-1168 3970);
DISPLAY 0.340426 (-1168 3970);
PAINT SKYBLUE (-1168 3970);
DISPLAY INVISIBLE (-1168 3970);
FORCEPROP 1 LAST BODY_TYPE PLUMBING
R 3
J 0
(-1168 3970);
DISPLAY 0.340426 (-1168 3970);
PAINT GREEN (-1168 3970);
DISPLAY INVISIBLE (-1168 3970);
FORCEPROP 1 LAST SIZE 1B
R 3
J 0
(-1175 3850);
DISPLAY 1.170213 (-1175 3850);
PAINT AQUA (-1175 3850);
DISPLAY INVISIBLE (-1175 3850);
FORCEPROP 2 LAST CDS_LIB mstr_symbols
J 0
(-1125 3925);
PAINT ORANGE (-1125 3925);
DISPLAY INVISIBLE (-1125 3925);
FORCEPROP 1 LAST PATH I122
R 3
J 0
(-1125 3850);
DISPLAY 0.872340 (-1125 3850);
PAINT AQUA (-1125 3850);
DISPLAY INVISIBLE (-1125 3850);
FORCEPROP 1 LAST HDL_POWER GND
R 3
J 0
(-975 3925);
DISPLAY 1.170213 (-975 3925);
PAINT GREEN (-975 3925);
DISPLAY INVISIBLE (-975 3925);
FORCEADD DIODE..1
(-1775 675);
FORCEPROP 1 LAST MATERIAL IC
J 0
(-1900 547);
DISPLAY 0.617021 (-1900 547);
PAINT SKYBLUE (-1900 547);
FORCEPROP 1 LASTPIN (-1875 675) $PN 2
J 2
(-1840 685);
DISPLAY 0.617021 (-1840 685);
PAINT AQUA (-1840 685);
FORCEPROP 1 LAST VALUE SDMK0340L
J 0
(-1800 550);
DISPLAY 0.617021 (-1800 550);
PAINT SKYBLUE (-1800 550);
FORCEPROP 1 LAST LOCATION CR1B3
J 0
(-1802 831);
DISPLAY 0.617021 (-1802 831);
PAINT AQUA (-1802 831);
FORCEPROP 1 LASTPIN (-1675 675) $PN 1
J 0
(-1710 685);
DISPLAY 0.617021 (-1710 685);
PAINT AQUA (-1710 685);
FORCEPROP 1 LAST PACK_TYPE SM
J 0
(-1575 560);
DISPLAY 0.617021 (-1575 560);
PAINT SKYBLUE (-1575 560);
FORCEPROP 1 LAST PART_NUMBER H71799-001
J 0
(-1800 775);
DISPLAY 0.617021 (-1800 775);
PAINT BLUE (-1800 775);
FORCEPROP 0 LAST ROOM CPU_FANS
J 0
(-1800 925);
DISPLAY 1.021277 (-1800 925);
PAINT ORANGE (-1800 925);
DISPLAY INVISIBLE (-1800 925);
FORCEPROP 1 LAST PATH I123
J 0
(-1795 885);
DISPLAY 0.978723 (-1795 885);
PAINT PINK (-1795 885);
DISPLAY INVISIBLE (-1795 885);
FORCEPROP 2 LAST CDS_LOCATION CR1B3
J 0
(-1802 831);
DISPLAY 0.617021 (-1802 831);
PAINT AQUA (-1802 831);
DISPLAY INVISIBLE (-1802 831);
FORCEPROP 2 LAST CDS_LIB mstr_discrete
J 0
(-1775 675);
PAINT ORANGE (-1775 675);
DISPLAY INVISIBLE (-1775 675);
FORCEPROP 2 LAST SEC_TYPE SM
J 0
(-1775 950);
DISPLAY 1.021277 (-1775 950);
PAINT ORANGE (-1775 950);
DISPLAY INVISIBLE (-1775 950);
FORCEPROP 2 LAST SEC 1
J 0
(-1775 950);
DISPLAY 0.680851 (-1775 950);
PAINT MONO (-1775 950);
DISPLAY INVISIBLE (-1775 950);
FORCEPROP 0 LAST BOM_COST SM_THERM
J 0
(-1800 1025);
DISPLAY 1.021277 (-1800 1025);
PAINT ORANGE (-1800 1025);
DISPLAY INVISIBLE (-1800 1025);
FORCEADD RES..1
(-2625 675);
FORCEPROP 1 LAST VALUE 100.0
J 2
(-2650 575);
DISPLAY 0.617021 (-2650 575);
PAINT SKYBLUE (-2650 575);
FORCEPROP 1 LAST WATTAGE 1/16W
J 2
(-2650 525);
DISPLAY 0.617021 (-2650 525);
PAINT SKYBLUE (-2650 525);
FORCEPROP 1 LASTPIN (-2725 675) $PN 1
J 0
(-2713 687);
DISPLAY 0.617021 (-2713 687);
PAINT ORANGE (-2713 687);
FORCEPROP 1 LAST TOLERANCE 1%
J 0
(-2625 575);
DISPLAY 0.617021 (-2625 575);
PAINT SKYBLUE (-2625 575);
FORCEPROP 1 LASTPIN (-2525 675) $PN 2
J 0
(-2563 687);
DISPLAY 0.617021 (-2563 687);
PAINT ORANGE (-2563 687);
FORCEPROP 1 LAST MATERIAL CHIP
J 0
(-2625 525);
DISPLAY 0.617021 (-2625 525);
PAINT SKYBLUE (-2625 525);
FORCEPROP 1 LAST PART_NUMBER G21796-017
J 0
(-2675 775);
DISPLAY 0.617021 (-2675 775);
PAINT BLUE (-2675 775);
FORCEPROP 1 LAST LOCATION R1B23
J 0
(-2675 725);
DISPLAY 0.617021 (-2675 725);
PAINT AQUA (-2675 725);
FORCEPROP 1 LAST PACK_TYPE 0402
J 0
(-2525 575);
DISPLAY 0.617021 (-2525 575);
PAINT SKYBLUE (-2525 575);
FORCEPROP 2 LAST CDS_LOCATION R1B23
J 0
(-2675 725);
DISPLAY 0.617021 (-2675 725);
PAINT AQUA (-2675 725);
DISPLAY INVISIBLE (-2675 725);
FORCEPROP 2 LAST CDS_LIB mstr_discrete
J 0
(-2625 675);
PAINT ORANGE (-2625 675);
DISPLAY INVISIBLE (-2625 675);
FORCEPROP 2 LAST SEC_TYPE 0402
J 0
(-2675 875);
DISPLAY 1.021277 (-2675 875);
PAINT ORANGE (-2675 875);
DISPLAY INVISIBLE (-2675 875);
FORCEPROP 0 LAST BOM_COST SM_THERM
J 0
(-2675 975);
DISPLAY 1.021277 (-2675 975);
PAINT ORANGE (-2675 975);
DISPLAY INVISIBLE (-2675 975);
FORCEPROP 2 LAST SEC 1
J 0
(-2675 875);
DISPLAY 0.680851 (-2675 875);
PAINT MONO (-2675 875);
DISPLAY INVISIBLE (-2675 875);
FORCEPROP 1 LAST PATH I124
J 0
(-2675 825);
DISPLAY 0.978723 (-2675 825);
PAINT WHITE (-2675 825);
DISPLAY INVISIBLE (-2675 825);
FORCEPROP 0 LAST ROOM CPU_FANS
J 0
(-2675 875);
DISPLAY 1.021277 (-2675 875);
PAINT ORANGE (-2675 875);
DISPLAY INVISIBLE (-2675 875);
FORCEADD RES..2
R 2
(-2925 825);
FORCEPROP 1 LAST PACK_TYPE 0402
J 2
(-3090 800);
DISPLAY 0.617021 (-3090 800);
PAINT SKYBLUE (-3090 800);
FORCEPROP 1 LAST WATTAGE 1/16W
J 2
(-2965 800);
DISPLAY 0.617021 (-2965 800);
PAINT SKYBLUE (-2965 800);
FORCEPROP 1 LAST MATERIAL CHIP
J 2
(-2965 750);
DISPLAY 0.617021 (-2965 750);
PAINT SKYBLUE (-2965 750);
FORCEPROP 1 LAST VALUE 4.75K
J 2
(-2970 900);
DISPLAY 0.617021 (-2970 900);
PAINT SKYBLUE (-2970 900);
FORCEPROP 1 LAST PART_NUMBER G21796-072
J 2
(-2965 700);
DISPLAY 0.617021 (-2965 700);
PAINT BLUE (-2965 700);
FORCEPROP 1 LAST LOCATION R1B24
J 2
(-2970 950);
DISPLAY 0.617021 (-2970 950);
PAINT AQUA (-2970 950);
FORCEPROP 1 LASTPIN (-2925 725) $PN 2
J 2
(-2930 735);
DISPLAY 0.617021 (-2930 735);
PAINT ORANGE (-2930 735);
FORCEPROP 1 LAST TOLERANCE 1%
J 2
(-2970 850);
DISPLAY 0.617021 (-2970 850);
PAINT SKYBLUE (-2970 850);
FORCEPROP 1 LASTPIN (-2925 925) $PN 1
J 2
(-2930 887);
DISPLAY 0.617021 (-2930 887);
PAINT ORANGE (-2930 887);
FORCEPROP 2 LAST CDS_LOCATION R1B24
J 2
(-2970 950);
DISPLAY 0.617021 (-2970 950);
PAINT AQUA (-2970 950);
DISPLAY INVISIBLE (-2970 950);
FORCEPROP 2 LAST CDS_LIB mstr_discrete
J 0
(-2925 825);
PAINT ORANGE (-2925 825);
DISPLAY INVISIBLE (-2925 825);
FORCEPROP 1 LAST PATH I126
J 2
(-2975 1000);
DISPLAY 0.978723 (-2975 1000);
PAINT WHITE (-2975 1000);
DISPLAY INVISIBLE (-2975 1000);
FORCEPROP 0 LAST ROOM CPU_FANS
J 0
(-2950 1050);
DISPLAY 1.021277 (-2950 1050);
PAINT ORANGE (-2950 1050);
DISPLAY INVISIBLE (-2950 1050);
FORCEPROP 2 LAST SEC 1
J 0
(-2975 1050);
DISPLAY 0.680851 (-2975 1050);
PAINT MONO (-2975 1050);
DISPLAY INVISIBLE (-2975 1050);
FORCEPROP 0 LAST BOM_COST SM_THERM
J 0
(-2950 1150);
DISPLAY 1.021277 (-2950 1150);
PAINT ORANGE (-2950 1150);
DISPLAY INVISIBLE (-2950 1150);
FORCEPROP 2 LAST SEC_TYPE 0402
J 0
(-2975 1050);
DISPLAY 1.021277 (-2975 1050);
PAINT ORANGE (-2975 1050);
DISPLAY INVISIBLE (-2975 1050);
FORCEADD CAP_A..1
R 2
(-3175 550);
FORCEPROP 1 LAST PACK_TYPE 0402V
J 2
(-3225 350);
DISPLAY 0.617021 (-3225 350);
PAINT SKYBLUE (-3225 350);
FORCEPROP 1 LAST PART_NUMBER A36096-045
J 2
(-3225 400);
DISPLAY 0.617021 (-3225 400);
PAINT BLUE (-3225 400);
FORCEPROP 1 LAST MATERIAL X7R
J 2
(-3225 450);
DISPLAY 0.617021 (-3225 450);
PAINT SKYBLUE (-3225 450);
FORCEPROP 1 LASTPIN (-3175 450) $PN 2
J 2
(-3185 430);
DISPLAY 0.617021 (-3185 430);
PAINT ORANGE (-3185 430);
FORCEPROP 1 LAST TOLERANCE 10%
J 2
(-3225 500);
DISPLAY 0.617021 (-3225 500);
PAINT SKYBLUE (-3225 500);
FORCEPROP 1 LAST VALUE 0.01UF
J 2
(-3225 600);
DISPLAY 0.617021 (-3225 600);
PAINT SKYBLUE (-3225 600);
FORCEPROP 1 LAST VOLTAGE 25V
J 2
(-3225 550);
DISPLAY 0.617021 (-3225 550);
PAINT SKYBLUE (-3225 550);
FORCEPROP 1 LASTPIN (-3175 650) $PN 1
J 2
(-3185 630);
DISPLAY 0.617021 (-3185 630);
PAINT ORANGE (-3185 630);
FORCEPROP 1 LAST LOCATION C1B17
J 2
(-2975 550);
DISPLAY 0.617021 (-2975 550);
PAINT AQUA (-2975 550);
FORCEPROP 0 LAST ROOM CPU_FANS
J 0
(-3225 700);
DISPLAY 1.021277 (-3225 700);
PAINT ORANGE (-3225 700);
DISPLAY INVISIBLE (-3225 700);
FORCEPROP 1 LAST PATH I128
J 2
(-3225 700);
DISPLAY 0.978723 (-3225 700);
PAINT WHITE (-3225 700);
DISPLAY INVISIBLE (-3225 700);
FORCEPROP 2 LAST CDS_SEC 1
J 0
(-3225 650);
PAINT ORANGE (-3225 650);
DISPLAY INVISIBLE (-3225 650);
FORCEPROP 0 LAST BOM_COST SM_THERM
J 0
(-3225 700);
DISPLAY 1.021277 (-3225 700);
PAINT ORANGE (-3225 700);
DISPLAY INVISIBLE (-3225 700);
FORCEPROP 2 LAST CDS_LIB dev_discrete
J 0
(-3175 550);
PAINT ORANGE (-3175 550);
DISPLAY INVISIBLE (-3175 550);
FORCEPROP 2 LAST SEC_TYPE 0402V
J 0
(-3225 750);
DISPLAY 1.021277 (-3225 750);
PAINT ORANGE (-3225 750);
DISPLAY INVISIBLE (-3225 750);
FORCEPROP 2 LAST SEC 1
J 0
(-3225 750);
DISPLAY 0.680851 (-3225 750);
PAINT MONO (-3225 750);
DISPLAY INVISIBLE (-3225 750);
FORCEPROP 2 LAST CDS_LOCATION C1B17
J 2
(-2975 550);
DISPLAY 0.617021 (-2975 550);
PAINT AQUA (-2975 550);
DISPLAY INVISIBLE (-2975 550);
FORCEADD GND..1
(-3175 375);
FORCEPROP 3 LASTPIN (-3175 425) SIG_NAME GND\g
J 0
(-3165 435);
DISPLAY 0.659574 (-3165 435);
PAINT MONO (-3165 435);
DISPLAY INVISIBLE (-3165 435);
FORCEPROP 1 LAST VOLTAGE 0.0V
J 0
(-3220 332);
DISPLAY 0.340426 (-3220 332);
PAINT SKYBLUE (-3220 332);
DISPLAY INVISIBLE (-3220 332);
FORCEPROP 1 LAST BODY_TYPE PLUMBING
J 0
(-3220 332);
DISPLAY 0.340426 (-3220 332);
PAINT GREEN (-3220 332);
DISPLAY INVISIBLE (-3220 332);
FORCEPROP 2 LAST CDS_LIB mstr_symbols
J 0
(-3175 375);
PAINT ORANGE (-3175 375);
DISPLAY INVISIBLE (-3175 375);
FORCEPROP 1 LAST SIZE 1B
J 0
(-3100 325);
DISPLAY 1.170213 (-3100 325);
PAINT AQUA (-3100 325);
DISPLAY INVISIBLE (-3100 325);
FORCEPROP 1 LAST PATH I129
J 0
(-3100 375);
DISPLAY 0.872340 (-3100 375);
PAINT AQUA (-3100 375);
DISPLAY INVISIBLE (-3100 375);
FORCEPROP 1 LAST HDL_POWER GND
J 0
(-3175 525);
DISPLAY 1.170213 (-3175 525);
PAINT GREEN (-3175 525);
DISPLAY INVISIBLE (-3175 525);
FORCEADD GND..1
(-1125 4075);
FORCEPROP 3 LASTPIN (-1125 4125) SIG_NAME GND\g
J 0
(-1115 4135);
DISPLAY 0.659574 (-1115 4135);
PAINT MONO (-1115 4135);
DISPLAY INVISIBLE (-1115 4135);
FORCEPROP 1 LAST BODY_TYPE PLUMBING
J 0
(-1170 4032);
DISPLAY 0.340426 (-1170 4032);
PAINT GREEN (-1170 4032);
DISPLAY INVISIBLE (-1170 4032);
FORCEPROP 1 LAST VOLTAGE 0.0V
J 0
(-1170 4032);
DISPLAY 0.340426 (-1170 4032);
PAINT SKYBLUE (-1170 4032);
DISPLAY INVISIBLE (-1170 4032);
FORCEPROP 1 LAST SIZE 1B
J 0
(-1050 4025);
DISPLAY 1.170213 (-1050 4025);
PAINT AQUA (-1050 4025);
DISPLAY INVISIBLE (-1050 4025);
FORCEPROP 1 LAST PATH I13
J 0
(-1050 4075);
DISPLAY 0.872340 (-1050 4075);
PAINT AQUA (-1050 4075);
DISPLAY INVISIBLE (-1050 4075);
FORCEPROP 2 LAST CDS_LIB mstr_symbols
J 0
(-1125 4075);
PAINT ORANGE (-1125 4075);
DISPLAY INVISIBLE (-1125 4075);
FORCEPROP 1 LAST HDL_POWER GND
J 0
(-1125 4225);
DISPLAY 1.170213 (-1125 4225);
PAINT GREEN (-1125 4225);
DISPLAY INVISIBLE (-1125 4225);
FORCEADD P3V3_STBY..1
(-2925 1000);
FORCEPROP 3 LASTPIN (-2925 950) SIG_NAME P3V3_STBY\g
J 0
(-2915 960);
DISPLAY 0.659574 (-2915 960);
PAINT MONO (-2915 960);
DISPLAY INVISIBLE (-2915 960);
FORCEPROP 1 LAST HDL_POWER P3V3_STBY
J 0
(-3225 875);
DISPLAY 0.872340 (-3225 875);
PAINT ORANGE (-3225 875);
DISPLAY INVISIBLE (-3225 875);
FORCEPROP 1 LAST BODY_TYPE PLUMBING
J 0
(-2970 957);
DISPLAY 0.340426 (-2970 957);
PAINT GREEN (-2970 957);
DISPLAY INVISIBLE (-2970 957);
FORCEPROP 1 LAST VOLTAGE 3.3V
J 0
(-2970 957);
DISPLAY 0.340426 (-2970 957);
PAINT SKYBLUE (-2970 957);
DISPLAY INVISIBLE (-2970 957);
FORCEPROP 1 LAST PATH I130
J 0
(-2880 1002);
DISPLAY 0.340426 (-2880 1002);
PAINT GREEN (-2880 1002);
DISPLAY INVISIBLE (-2880 1002);
FORCEPROP 2 LAST CDS_LIB mstr_symbols
J 0
(-2925 1000);
PAINT ORANGE (-2925 1000);
DISPLAY INVISIBLE (-2925 1000);
FORCEPROP 1 LAST SIZE 1B
J 0
(-2880 1022);
DISPLAY 0.340426 (-2880 1022);
PAINT GREEN (-2880 1022);
DISPLAY INVISIBLE (-2880 1022);
FORCEADD OFFPAGE..2
R 2
(-3575 675);
FORCEPROP 2 LAST $XR0 181 
J 0
(-3830 675);
DISPLAY 0.638298 (-3830 675);
PAINT MONO (-3830 675);
FORCEPROP 2 LAST $XR1 120 
J 0
(-3950 675);
DISPLAY 0.638298 (-3950 675);
PAINT MONO (-3950 675);
FORCEPROP 2 LAST $XR2 147 
J 0
(-4070 675);
DISPLAY 0.638298 (-4070 675);
PAINT MONO (-4070 675);
FORCEPROP 1 LAST OFFPAGE TRUE
J 2
(-3900 550);
DISPLAY 0.872340 (-3900 550);
PAINT GREEN (-3900 550);
DISPLAY INVISIBLE (-3900 550);
FORCEPROP 2 LAST PATH I131
J 0
(-3525 750);
DISPLAY 1.021277 (-3525 750);
PAINT ORANGE (-3525 750);
DISPLAY INVISIBLE (-3525 750);
FORCEPROP 2 LAST CDS_LIB mstr_standard
J 0
(-3575 675);
PAINT ORANGE (-3575 675);
DISPLAY INVISIBLE (-3575 675);
FORCEPROP 1 LAST COMMENT_BODY TRUE
J 2
(-3530 580);
DISPLAY 0.872340 (-3530 580);
PAINT GREEN (-3530 580);
DISPLAY INVISIBLE (-3530 580);
FORCEADD GND..1
(-3300 2400);
FORCEPROP 3 LASTPIN (-3300 2450) SIG_NAME GND\g
J 0
(-3290 2460);
DISPLAY 0.659574 (-3290 2460);
PAINT MONO (-3290 2460);
DISPLAY INVISIBLE (-3290 2460);
FORCEPROP 1 LAST VOLTAGE 0.0V
J 0
(-3345 2357);
DISPLAY 0.340426 (-3345 2357);
PAINT SKYBLUE (-3345 2357);
DISPLAY INVISIBLE (-3345 2357);
FORCEPROP 1 LAST BODY_TYPE PLUMBING
J 0
(-3345 2357);
DISPLAY 0.340426 (-3345 2357);
PAINT GREEN (-3345 2357);
DISPLAY INVISIBLE (-3345 2357);
FORCEPROP 1 LAST PATH I132
J 0
(-3225 2400);
DISPLAY 0.872340 (-3225 2400);
PAINT AQUA (-3225 2400);
DISPLAY INVISIBLE (-3225 2400);
FORCEPROP 2 LAST CDS_LIB mstr_symbols
J 0
(-3300 2400);
PAINT ORANGE (-3300 2400);
DISPLAY INVISIBLE (-3300 2400);
FORCEPROP 1 LAST SIZE 1B
J 0
(-3225 2350);
DISPLAY 1.170213 (-3225 2350);
PAINT AQUA (-3225 2350);
DISPLAY INVISIBLE (-3225 2350);
FORCEPROP 1 LAST HDL_POWER GND
J 0
(-3300 2550);
DISPLAY 1.170213 (-3300 2550);
PAINT GREEN (-3300 2550);
DISPLAY INVISIBLE (-3300 2550);
FORCEADD DIODE..1
(-1975 2775);
FORCEPROP 1 LASTPIN (-2075 2775) $PN 2
J 2
(-2040 2785);
DISPLAY 0.617021 (-2040 2785);
PAINT AQUA (-2040 2785);
FORCEPROP 1 LAST MATERIAL IC
J 0
(-2100 2647);
DISPLAY 0.617021 (-2100 2647);
PAINT SKYBLUE (-2100 2647);
FORCEPROP 1 LASTPIN (-1875 2775) $PN 1
J 0
(-1910 2785);
DISPLAY 0.617021 (-1910 2785);
PAINT AQUA (-1910 2785);
FORCEPROP 1 LAST LOCATION CR1F2
J 0
(-2002 2931);
DISPLAY 0.617021 (-2002 2931);
PAINT AQUA (-2002 2931);
FORCEPROP 1 LAST VALUE SDMK0340L
J 0
(-2000 2650);
DISPLAY 0.617021 (-2000 2650);
PAINT SKYBLUE (-2000 2650);
FORCEPROP 1 LAST PART_NUMBER H71799-001
J 0
(-2000 2875);
DISPLAY 0.617021 (-2000 2875);
PAINT BLUE (-2000 2875);
FORCEPROP 1 LAST PACK_TYPE SM
J 0
(-1775 2660);
DISPLAY 0.617021 (-1775 2660);
PAINT SKYBLUE (-1775 2660);
FORCEPROP 0 LAST ROOM CPU_FANS
J 0
(-2000 3025);
DISPLAY 1.021277 (-2000 3025);
PAINT ORANGE (-2000 3025);
DISPLAY INVISIBLE (-2000 3025);
FORCEPROP 1 LAST PATH I133
J 0
(-1995 2985);
DISPLAY 0.978723 (-1995 2985);
PAINT PINK (-1995 2985);
DISPLAY INVISIBLE (-1995 2985);
FORCEPROP 2 LAST CDS_LOCATION CR1F2
J 0
(-2002 2931);
DISPLAY 0.617021 (-2002 2931);
PAINT AQUA (-2002 2931);
DISPLAY INVISIBLE (-2002 2931);
FORCEPROP 2 LAST CDS_LIB mstr_discrete
J 0
(-1975 2775);
PAINT ORANGE (-1975 2775);
DISPLAY INVISIBLE (-1975 2775);
FORCEPROP 2 LAST SEC 1
J 0
(-1975 3050);
DISPLAY 0.680851 (-1975 3050);
PAINT MONO (-1975 3050);
DISPLAY INVISIBLE (-1975 3050);
FORCEPROP 2 LAST SEC_TYPE SM
J 0
(-1975 3050);
DISPLAY 1.021277 (-1975 3050);
PAINT ORANGE (-1975 3050);
DISPLAY INVISIBLE (-1975 3050);
FORCEPROP 0 LAST BOM_COST SM_THERM
J 0
(-2000 3125);
DISPLAY 1.021277 (-2000 3125);
PAINT ORANGE (-2000 3125);
DISPLAY INVISIBLE (-2000 3125);
FORCEADD RES..1
(-2850 2775);
FORCEPROP 1 LASTPIN (-2950 2775) $PN 1
J 0
(-2938 2787);
DISPLAY 0.617021 (-2938 2787);
PAINT ORANGE (-2938 2787);
FORCEPROP 1 LAST WATTAGE 1/16W
J 2
(-2875 2625);
DISPLAY 0.617021 (-2875 2625);
PAINT SKYBLUE (-2875 2625);
FORCEPROP 1 LAST VALUE 100.0
J 2
(-2875 2675);
DISPLAY 0.617021 (-2875 2675);
PAINT SKYBLUE (-2875 2675);
FORCEPROP 1 LAST MATERIAL CHIP
J 0
(-2850 2625);
DISPLAY 0.617021 (-2850 2625);
PAINT SKYBLUE (-2850 2625);
FORCEPROP 1 LAST LOCATION R9T7
J 0
(-2900 2825);
DISPLAY 0.617021 (-2900 2825);
PAINT AQUA (-2900 2825);
FORCEPROP 1 LAST PART_NUMBER G21796-017
J 0
(-2900 2875);
DISPLAY 0.617021 (-2900 2875);
PAINT BLUE (-2900 2875);
FORCEPROP 1 LAST TOLERANCE 1%
J 0
(-2850 2675);
DISPLAY 0.617021 (-2850 2675);
PAINT SKYBLUE (-2850 2675);
FORCEPROP 1 LASTPIN (-2750 2775) $PN 2
J 0
(-2788 2787);
DISPLAY 0.617021 (-2788 2787);
PAINT ORANGE (-2788 2787);
FORCEPROP 1 LAST PACK_TYPE 0402
J 0
(-2750 2675);
DISPLAY 0.617021 (-2750 2675);
PAINT SKYBLUE (-2750 2675);
FORCEPROP 2 LAST CDS_LIB mstr_discrete
J 0
(-2850 2775);
PAINT ORANGE (-2850 2775);
DISPLAY INVISIBLE (-2850 2775);
FORCEPROP 2 LAST CDS_LOCATION R9T7
J 0
(-2900 2825);
DISPLAY 0.617021 (-2900 2825);
PAINT AQUA (-2900 2825);
DISPLAY INVISIBLE (-2900 2825);
FORCEPROP 2 LAST SEC 1
J 0
(-2900 2975);
DISPLAY 0.680851 (-2900 2975);
PAINT MONO (-2900 2975);
DISPLAY INVISIBLE (-2900 2975);
FORCEPROP 2 LAST SEC_TYPE 0402
J 0
(-2900 2975);
DISPLAY 1.021277 (-2900 2975);
PAINT ORANGE (-2900 2975);
DISPLAY INVISIBLE (-2900 2975);
FORCEPROP 0 LAST ROOM CPU_FANS
J 0
(-2900 2975);
DISPLAY 1.021277 (-2900 2975);
PAINT ORANGE (-2900 2975);
DISPLAY INVISIBLE (-2900 2975);
FORCEPROP 1 LAST PATH I134
J 0
(-2900 2925);
DISPLAY 0.978723 (-2900 2925);
PAINT WHITE (-2900 2925);
DISPLAY INVISIBLE (-2900 2925);
FORCEPROP 0 LAST BOM_COST SM_THERM
J 0
(-2900 3075);
DISPLAY 1.021277 (-2900 3075);
PAINT ORANGE (-2900 3075);
DISPLAY INVISIBLE (-2900 3075);
FORCEADD RES..2
R 2
(-3225 2925);
FORCEPROP 1 LAST PART_NUMBER G21796-072
J 2
(-3490 2900);
DISPLAY 0.617021 (-3490 2900);
PAINT BLUE (-3490 2900);
FORCEPROP 1 LAST PACK_TYPE 0402
J 2
(-3390 2900);
DISPLAY 0.617021 (-3390 2900);
PAINT SKYBLUE (-3390 2900);
FORCEPROP 1 LAST WATTAGE 1/16W
J 2
(-3265 2900);
DISPLAY 0.617021 (-3265 2900);
PAINT SKYBLUE (-3265 2900);
FORCEPROP 1 LAST MATERIAL CHIP
J 2
(-3265 2850);
DISPLAY 0.617021 (-3265 2850);
PAINT SKYBLUE (-3265 2850);
FORCEPROP 1 LAST TOLERANCE 1%
J 2
(-3270 2950);
DISPLAY 0.617021 (-3270 2950);
PAINT SKYBLUE (-3270 2950);
FORCEPROP 1 LAST VALUE 4.75K
J 2
(-3270 3000);
DISPLAY 0.617021 (-3270 3000);
PAINT SKYBLUE (-3270 3000);
FORCEPROP 1 LASTPIN (-3225 2825) $PN 2
J 2
(-3230 2835);
DISPLAY 0.617021 (-3230 2835);
PAINT ORANGE (-3230 2835);
FORCEPROP 1 LASTPIN (-3225 3025) $PN 1
J 2
(-3230 2987);
DISPLAY 0.617021 (-3230 2987);
PAINT ORANGE (-3230 2987);
FORCEPROP 1 LAST LOCATION R9T5
J 2
(-3270 3050);
DISPLAY 0.617021 (-3270 3050);
PAINT AQUA (-3270 3050);
FORCEPROP 2 LAST CDS_LIB mstr_discrete
J 0
(-3225 2925);
PAINT ORANGE (-3225 2925);
DISPLAY INVISIBLE (-3225 2925);
FORCEPROP 2 LAST CDS_LOCATION R9T5
J 2
(-3270 3050);
DISPLAY 0.617021 (-3270 3050);
PAINT AQUA (-3270 3050);
DISPLAY INVISIBLE (-3270 3050);
FORCEPROP 0 LAST ROOM CPU_FANS
J 0
(-3250 3150);
DISPLAY 1.021277 (-3250 3150);
PAINT ORANGE (-3250 3150);
DISPLAY INVISIBLE (-3250 3150);
FORCEPROP 1 LAST PATH I135
J 2
(-3275 3100);
DISPLAY 0.978723 (-3275 3100);
PAINT WHITE (-3275 3100);
DISPLAY INVISIBLE (-3275 3100);
FORCEPROP 2 LAST SEC 1
J 0
(-3275 3150);
DISPLAY 0.680851 (-3275 3150);
PAINT MONO (-3275 3150);
DISPLAY INVISIBLE (-3275 3150);
FORCEPROP 2 LAST SEC_TYPE 0402
J 0
(-3275 3150);
DISPLAY 1.021277 (-3275 3150);
PAINT ORANGE (-3275 3150);
DISPLAY INVISIBLE (-3275 3150);
FORCEPROP 0 LAST BOM_COST SM_THERM
J 0
(-3250 3250);
DISPLAY 1.021277 (-3250 3250);
PAINT ORANGE (-3250 3250);
DISPLAY INVISIBLE (-3250 3250);
FORCEADD P3V3_STBY..1
(-3225 3100);
FORCEPROP 3 LASTPIN (-3225 3050) SIG_NAME P3V3_STBY\g
J 0
(-3215 3060);
DISPLAY 0.659574 (-3215 3060);
PAINT MONO (-3215 3060);
DISPLAY INVISIBLE (-3215 3060);
FORCEPROP 1 LAST HDL_POWER P3V3_STBY
J 0
(-3525 2975);
DISPLAY 0.872340 (-3525 2975);
PAINT ORANGE (-3525 2975);
DISPLAY INVISIBLE (-3525 2975);
FORCEPROP 1 LAST BODY_TYPE PLUMBING
J 0
(-3270 3057);
DISPLAY 0.340426 (-3270 3057);
PAINT GREEN (-3270 3057);
DISPLAY INVISIBLE (-3270 3057);
FORCEPROP 1 LAST VOLTAGE 3.3V
J 0
(-3270 3057);
DISPLAY 0.340426 (-3270 3057);
PAINT SKYBLUE (-3270 3057);
DISPLAY INVISIBLE (-3270 3057);
FORCEPROP 1 LAST PATH I136
J 0
(-3180 3102);
DISPLAY 0.340426 (-3180 3102);
PAINT GREEN (-3180 3102);
DISPLAY INVISIBLE (-3180 3102);
FORCEPROP 2 LAST CDS_LIB mstr_symbols
J 0
(-3225 3100);
PAINT ORANGE (-3225 3100);
DISPLAY INVISIBLE (-3225 3100);
FORCEPROP 1 LAST SIZE 1B
J 0
(-3180 3122);
DISPLAY 0.340426 (-3180 3122);
PAINT GREEN (-3180 3122);
DISPLAY INVISIBLE (-3180 3122);
FORCEADD CAP_A..1
R 2
(-3300 2625);
FORCEPROP 1 LAST PART_NUMBER A36096-045
J 2
(-3350 2475);
DISPLAY 0.617021 (-3350 2475);
PAINT BLUE (-3350 2475);
FORCEPROP 1 LAST PACK_TYPE 0402V
J 2
(-3350 2425);
DISPLAY 0.617021 (-3350 2425);
PAINT SKYBLUE (-3350 2425);
FORCEPROP 1 LAST MATERIAL X7R
J 2
(-3350 2525);
DISPLAY 0.617021 (-3350 2525);
PAINT SKYBLUE (-3350 2525);
FORCEPROP 1 LASTPIN (-3300 2525) $PN 2
J 2
(-3310 2505);
DISPLAY 0.617021 (-3310 2505);
PAINT ORANGE (-3310 2505);
FORCEPROP 1 LAST VOLTAGE 25V
J 2
(-3350 2625);
DISPLAY 0.617021 (-3350 2625);
PAINT SKYBLUE (-3350 2625);
FORCEPROP 1 LAST TOLERANCE 10%
J 2
(-3350 2575);
DISPLAY 0.617021 (-3350 2575);
PAINT SKYBLUE (-3350 2575);
FORCEPROP 1 LAST VALUE 0.01UF
J 2
(-3350 2675);
DISPLAY 0.617021 (-3350 2675);
PAINT SKYBLUE (-3350 2675);
FORCEPROP 1 LASTPIN (-3300 2725) $PN 1
J 2
(-3310 2705);
DISPLAY 0.617021 (-3310 2705);
PAINT ORANGE (-3310 2705);
FORCEPROP 1 LAST LOCATION C9T1
J 2
(-3100 2625);
DISPLAY 0.617021 (-3100 2625);
PAINT AQUA (-3100 2625);
FORCEPROP 0 LAST ROOM CPU_FANS
J 0
(-3350 2775);
DISPLAY 1.021277 (-3350 2775);
PAINT ORANGE (-3350 2775);
DISPLAY INVISIBLE (-3350 2775);
FORCEPROP 1 LAST PATH I137
J 2
(-3350 2775);
DISPLAY 0.978723 (-3350 2775);
PAINT WHITE (-3350 2775);
DISPLAY INVISIBLE (-3350 2775);
FORCEPROP 2 LAST SEC 1
J 0
(-3350 2825);
DISPLAY 0.680851 (-3350 2825);
PAINT MONO (-3350 2825);
DISPLAY INVISIBLE (-3350 2825);
FORCEPROP 2 LAST SEC_TYPE 0402V
J 0
(-3350 2825);
DISPLAY 1.021277 (-3350 2825);
PAINT ORANGE (-3350 2825);
DISPLAY INVISIBLE (-3350 2825);
FORCEPROP 2 LAST CDS_SEC 1
J 0
(-3350 2725);
PAINT ORANGE (-3350 2725);
DISPLAY INVISIBLE (-3350 2725);
FORCEPROP 0 LAST BOM_COST SM_THERM
J 0
(-3350 2775);
DISPLAY 1.021277 (-3350 2775);
PAINT ORANGE (-3350 2775);
DISPLAY INVISIBLE (-3350 2775);
FORCEPROP 2 LAST CDS_LIB dev_discrete
J 0
(-3300 2625);
PAINT ORANGE (-3300 2625);
DISPLAY INVISIBLE (-3300 2625);
FORCEPROP 2 LAST CDS_LOCATION C9T1
J 2
(-3100 2625);
DISPLAY 0.617021 (-3100 2625);
PAINT AQUA (-3100 2625);
DISPLAY INVISIBLE (-3100 2625);
FORCEADD OFFPAGE..2
R 2
(-3625 2775);
FORCEPROP 2 LAST $XR0 181 
J 0
(-3910 2775);
DISPLAY 0.638298 (-3910 2775);
PAINT MONO (-3910 2775);
FORCEPROP 2 LAST $XR1 120 
J 0
(-4030 2775);
DISPLAY 0.638298 (-4030 2775);
PAINT MONO (-4030 2775);
FORCEPROP 2 LAST $XR2 147 
J 0
(-4150 2775);
DISPLAY 0.638298 (-4150 2775);
PAINT MONO (-4150 2775);
FORCEPROP 1 LAST OFFPAGE TRUE
J 2
(-3950 2650);
DISPLAY 0.872340 (-3950 2650);
PAINT GREEN (-3950 2650);
DISPLAY INVISIBLE (-3950 2650);
FORCEPROP 2 LAST CDS_LIB mstr_standard
J 0
(-3625 2775);
PAINT ORANGE (-3625 2775);
DISPLAY INVISIBLE (-3625 2775);
FORCEPROP 2 LAST PATH I138
J 0
(-3575 2850);
DISPLAY 1.021277 (-3575 2850);
PAINT ORANGE (-3575 2850);
DISPLAY INVISIBLE (-3575 2850);
FORCEPROP 1 LAST COMMENT_BODY TRUE
J 2
(-3580 2680);
DISPLAY 0.872340 (-3580 2680);
PAINT GREEN (-3580 2680);
DISPLAY INVISIBLE (-3580 2680);
FORCEADD CAP_A..1
(-1000 2275);
FORCEPROP 1 LASTPIN (-1000 2175) $PN 2
J 0
(-990 2155);
DISPLAY 0.617021 (-990 2155);
PAINT ORANGE (-990 2155);
FORCEPROP 1 LAST PACK_TYPE 0402V
J 0
(-950 2075);
DISPLAY 0.617021 (-950 2075);
PAINT SKYBLUE (-950 2075);
FORCEPROP 1 LAST TOLERANCE 10%
J 0
(-950 2225);
DISPLAY 0.617021 (-950 2225);
PAINT SKYBLUE (-950 2225);
FORCEPROP 1 LAST VOLTAGE 16V
J 0
(-950 2275);
DISPLAY 0.617021 (-950 2275);
PAINT SKYBLUE (-950 2275);
FORCEPROP 1 LAST MATERIAL X7R
J 0
(-950 2175);
DISPLAY 0.617021 (-950 2175);
PAINT SKYBLUE (-950 2175);
FORCEPROP 1 LASTPIN (-1000 2375) $PN 1
J 0
(-990 2355);
DISPLAY 0.617021 (-990 2355);
PAINT ORANGE (-990 2355);
FORCEPROP 1 LAST LOCATION C9M5
J 0
(-950 2375);
DISPLAY 0.617021 (-950 2375);
PAINT AQUA (-950 2375);
FORCEPROP 1 LAST VALUE 0.1UF
J 0
(-950 2325);
DISPLAY 0.617021 (-950 2325);
PAINT SKYBLUE (-950 2325);
FORCEPROP 1 LAST PART_NUMBER A36096-030
J 0
(-950 2125);
DISPLAY 0.617021 (-950 2125);
PAINT BLUE (-950 2125);
FORCEPROP 2 LAST CDS_LIB dev_discrete
J 0
(-1000 2275);
PAINT ORANGE (-1000 2275);
DISPLAY INVISIBLE (-1000 2275);
FORCEPROP 1 LAST PATH I26
J 0
(-950 2425);
DISPLAY 0.978723 (-950 2425);
PAINT WHITE (-950 2425);
DISPLAY INVISIBLE (-950 2425);
FORCEPROP 0 LAST ROOM CPU_FANS
J 0
(-950 2475);
DISPLAY 1.021277 (-950 2475);
PAINT ORANGE (-950 2475);
DISPLAY INVISIBLE (-950 2475);
FORCEPROP 2 LAST SEC 1
J 0
(-950 2475);
DISPLAY 0.680851 (-950 2475);
PAINT MONO (-950 2475);
DISPLAY INVISIBLE (-950 2475);
FORCEPROP 2 LAST SEC_TYPE 0402V
J 0
(-950 2475);
DISPLAY 1.021277 (-950 2475);
PAINT ORANGE (-950 2475);
DISPLAY INVISIBLE (-950 2475);
FORCEPROP 2 LAST CDS_SEC 1
J 0
(-950 2425);
PAINT ORANGE (-950 2425);
DISPLAY INVISIBLE (-950 2425);
FORCEPROP 0 LAST BOM_COST SM_THERM
J 0
(-950 2425);
DISPLAY 1.021277 (-950 2425);
PAINT ORANGE (-950 2425);
DISPLAY INVISIBLE (-950 2425);
FORCEPROP 2 LAST CDS_LOCATION C9M5
J 0
(-950 2375);
DISPLAY 0.617021 (-950 2375);
PAINT AQUA (-950 2375);
DISPLAY INVISIBLE (-950 2375);
FORCEADD CAP..1
(-1300 2275);
FORCEPROP 1 LASTPIN (-1300 2175) $PN 2
J 0
(-1290 2155);
DISPLAY 0.617021 (-1290 2155);
PAINT ORANGE (-1290 2155);
FORCEPROP 1 LASTPIN (-1300 2375) $PN 1
J 0
(-1290 2355);
DISPLAY 0.617021 (-1290 2355);
PAINT ORANGE (-1290 2355);
FORCEPROP 1 LAST VOLTAGE 16V
J 0
(-1250 2275);
DISPLAY 0.617021 (-1250 2275);
PAINT SKYBLUE (-1250 2275);
FORCEPROP 1 LAST LOCATION C9M4
J 0
(-1250 2375);
DISPLAY 0.617021 (-1250 2375);
PAINT AQUA (-1250 2375);
FORCEPROP 1 LAST VALUE 10UF
J 0
(-1250 2325);
DISPLAY 0.617021 (-1250 2325);
PAINT SKYBLUE (-1250 2325);
FORCEPROP 1 LAST PACK_TYPE 0805
J 0
(-1250 2075);
DISPLAY 0.617021 (-1250 2075);
PAINT SKYBLUE (-1250 2075);
FORCEPROP 1 LAST TOLERANCE 10%
J 0
(-1250 2225);
DISPLAY 0.617021 (-1250 2225);
PAINT SKYBLUE (-1250 2225);
FORCEPROP 1 LAST PART_NUMBER C95333-007
J 0
(-1250 2125);
DISPLAY 0.617021 (-1250 2125);
PAINT BLUE (-1250 2125);
FORCEPROP 2 LAST CDS_LIB mstr_discrete
J 0
(-1300 2275);
PAINT ORANGE (-1300 2275);
DISPLAY INVISIBLE (-1300 2275);
FORCEPROP 1 LAST MATERIAL X6S
J 0
(-1250 2175);
DISPLAY 0.617021 (-1250 2175);
PAINT SKYBLUE (-1250 2175);
DISPLAY INVISIBLE (-1250 2175);
FORCEPROP 1 LAST PATH I27
J 0
(-1250 2425);
DISPLAY 0.978723 (-1250 2425);
PAINT WHITE (-1250 2425);
DISPLAY INVISIBLE (-1250 2425);
FORCEPROP 2 LAST CDS_LOCATION C9M4
J 0
(-1250 2375);
DISPLAY 0.617021 (-1250 2375);
PAINT AQUA (-1250 2375);
DISPLAY INVISIBLE (-1250 2375);
FORCEPROP 2 LAST SEC 1
J 0
(-1250 2475);
DISPLAY 0.680851 (-1250 2475);
PAINT MONO (-1250 2475);
DISPLAY INVISIBLE (-1250 2475);
FORCEPROP 2 LAST SEC_TYPE 0805
J 0
(-1250 2475);
DISPLAY 1.021277 (-1250 2475);
PAINT ORANGE (-1250 2475);
DISPLAY INVISIBLE (-1250 2475);
FORCEPROP 0 LAST BOM_COST SM_THERM
J 0
(-1250 2425);
DISPLAY 1.021277 (-1250 2425);
PAINT ORANGE (-1250 2425);
DISPLAY INVISIBLE (-1250 2425);
FORCEPROP 0 LAST ROOM CPU_FANS
J 0
(-1250 2475);
DISPLAY 1.021277 (-1250 2475);
PAINT ORANGE (-1250 2475);
DISPLAY INVISIBLE (-1250 2475);
FORCEADD CAP..1
(-1400 4350);
FORCEPROP 1 LASTPIN (-1400 4250) $PN 2
J 0
(-1390 4230);
DISPLAY 0.617021 (-1390 4230);
PAINT ORANGE (-1390 4230);
FORCEPROP 1 LASTPIN (-1400 4450) $PN 1
J 0
(-1390 4430);
DISPLAY 0.617021 (-1390 4430);
PAINT ORANGE (-1390 4430);
FORCEPROP 1 LAST VOLTAGE 16V
J 0
(-1350 4350);
DISPLAY 0.617021 (-1350 4350);
PAINT SKYBLUE (-1350 4350);
FORCEPROP 1 LAST PACK_TYPE 0805
J 0
(-1350 4150);
DISPLAY 0.617021 (-1350 4150);
PAINT SKYBLUE (-1350 4150);
FORCEPROP 1 LAST TOLERANCE 10%
J 0
(-1350 4300);
DISPLAY 0.617021 (-1350 4300);
PAINT SKYBLUE (-1350 4300);
FORCEPROP 1 LAST VALUE 10UF
J 0
(-1350 4400);
DISPLAY 0.617021 (-1350 4400);
PAINT SKYBLUE (-1350 4400);
FORCEPROP 1 LAST PART_NUMBER C95333-007
J 0
(-1350 4200);
DISPLAY 0.617021 (-1350 4200);
PAINT BLUE (-1350 4200);
FORCEPROP 1 LAST LOCATION C1E21
J 0
(-1350 4450);
DISPLAY 0.617021 (-1350 4450);
PAINT AQUA (-1350 4450);
FORCEPROP 1 LAST MATERIAL X6S
J 0
(-1350 4250);
DISPLAY 0.617021 (-1350 4250);
PAINT SKYBLUE (-1350 4250);
DISPLAY INVISIBLE (-1350 4250);
FORCEPROP 2 LAST CDS_LIB mstr_discrete
J 0
(-1400 4350);
PAINT ORANGE (-1400 4350);
DISPLAY INVISIBLE (-1400 4350);
FORCEPROP 0 LAST ROOM CPU_FANS
J 0
(-1350 4550);
DISPLAY 1.021277 (-1350 4550);
PAINT ORANGE (-1350 4550);
DISPLAY INVISIBLE (-1350 4550);
FORCEPROP 1 LAST PATH I3
J 0
(-1350 4500);
DISPLAY 0.978723 (-1350 4500);
PAINT WHITE (-1350 4500);
DISPLAY INVISIBLE (-1350 4500);
FORCEPROP 2 LAST CDS_LOCATION C1E21
J 0
(-1350 4450);
DISPLAY 0.617021 (-1350 4450);
PAINT AQUA (-1350 4450);
DISPLAY INVISIBLE (-1350 4450);
FORCEPROP 2 LAST SEC 1
J 0
(-1350 4550);
DISPLAY 0.680851 (-1350 4550);
PAINT MONO (-1350 4550);
DISPLAY INVISIBLE (-1350 4550);
FORCEPROP 0 LAST BOM_COST SM_THERM
J 0
(-1350 4500);
DISPLAY 1.021277 (-1350 4500);
PAINT ORANGE (-1350 4500);
DISPLAY INVISIBLE (-1350 4500);
FORCEPROP 2 LAST SEC_TYPE 0805
J 0
(-1350 4550);
DISPLAY 1.021277 (-1350 4550);
PAINT ORANGE (-1350 4550);
DISPLAY INVISIBLE (-1350 4550);
FORCEADD GND..1
(-1300 1950);
FORCEPROP 3 LASTPIN (-1300 2000) SIG_NAME GND\g
J 0
(-1290 2010);
DISPLAY 0.659574 (-1290 2010);
PAINT MONO (-1290 2010);
DISPLAY INVISIBLE (-1290 2010);
FORCEPROP 1 LAST BODY_TYPE PLUMBING
J 0
(-1345 1907);
DISPLAY 0.340426 (-1345 1907);
PAINT GREEN (-1345 1907);
DISPLAY INVISIBLE (-1345 1907);
FORCEPROP 2 LAST CDS_LIB mstr_symbols
J 0
(-1300 1950);
PAINT ORANGE (-1300 1950);
DISPLAY INVISIBLE (-1300 1950);
FORCEPROP 1 LAST VOLTAGE 0.0V
J 0
(-1345 1907);
DISPLAY 0.340426 (-1345 1907);
PAINT SKYBLUE (-1345 1907);
DISPLAY INVISIBLE (-1345 1907);
FORCEPROP 1 LAST PATH I30
J 0
(-1225 1950);
DISPLAY 0.872340 (-1225 1950);
PAINT AQUA (-1225 1950);
DISPLAY INVISIBLE (-1225 1950);
FORCEPROP 1 LAST SIZE 1B
J 0
(-1225 1900);
DISPLAY 1.170213 (-1225 1900);
PAINT AQUA (-1225 1900);
DISPLAY INVISIBLE (-1225 1900);
FORCEPROP 1 LAST HDL_POWER GND
J 0
(-1300 2100);
DISPLAY 1.170213 (-1300 2100);
PAINT GREEN (-1300 2100);
DISPLAY INVISIBLE (-1300 2100);
FORCEADD CONN6_C74770005..1
(-775 1700);
FORCEPROP 1 LAST PART_NUMBER C74770-005
J 0
(-825 1425);
DISPLAY 0.617021 (-825 1425);
PAINT BLUE (-825 1425);
FORCEPROP 2 LASTPIN (-875 1750) $PN 3
J 2
(-885 1760);
DISPLAY 0.617021 (-885 1760);
PAINT ORANGE (-885 1760);
FORCEPROP 2 LASTPIN (-875 1700) $PN 4
J 2
(-885 1710);
DISPLAY 0.617021 (-885 1710);
PAINT ORANGE (-885 1710);
FORCEPROP 2 LASTPIN (-875 1650) $PN 5
J 2
(-885 1660);
DISPLAY 0.617021 (-885 1660);
PAINT ORANGE (-885 1660);
FORCEPROP 2 LASTPIN (-875 1600) $PN 6
J 2
(-885 1610);
DISPLAY 0.617021 (-885 1610);
PAINT ORANGE (-885 1610);
FORCEPROP 2 LASTPIN (-875 1850) $PN 1
J 2
(-885 1860);
DISPLAY 0.617021 (-885 1860);
PAINT ORANGE (-885 1860);
FORCEPROP 2 LASTPIN (-875 1800) $PN 2
J 2
(-885 1810);
DISPLAY 0.617021 (-885 1810);
PAINT ORANGE (-885 1810);
FORCEPROP 1 LAST MATERIAL HDR
J 0
(-825 1975);
DISPLAY 0.617021 (-825 1975);
PAINT SKYBLUE (-825 1975);
FORCEPROP 1 LAST LOCATION J1B2
J 0
(-725 2000);
DISPLAY 0.617021 (-725 2000);
PAINT AQUA (-725 2000);
FORCEPROP 2 LAST CDS_LIB mstr_conn
J 0
(-775 1700);
PAINT ORANGE (-775 1700);
DISPLAY INVISIBLE (-775 1700);
FORCEPROP 2 LAST CDS_LOCATION J1B2
J 0
(-725 2000);
DISPLAY 0.617021 (-725 2000);
PAINT AQUA (-725 2000);
DISPLAY INVISIBLE (-725 2000);
FORCEPROP 1 LAST PATH I32
J 0
(-375 1975);
DISPLAY 0.978723 (-375 1975);
PAINT BLUE (-375 1975);
DISPLAY INVISIBLE (-375 1975);
FORCEPROP 0 LAST ROOM CPU_FANS
J 0
(-900 2075);
DISPLAY 1.021277 (-900 2075);
PAINT ORANGE (-900 2075);
DISPLAY INVISIBLE (-900 2075);
FORCEPROP 0 LAST BOM_COST SM_THERM
J 0
(-900 2125);
DISPLAY 1.021277 (-900 2125);
PAINT ORANGE (-900 2125);
DISPLAY INVISIBLE (-900 2125);
FORCEPROP 1 LAST PACK_TYPE PIP
J 0
(-825 2075);
DISPLAY 0.978723 (-825 2075);
PAINT SKYBLUE (-825 2075);
DISPLAY INVISIBLE (-825 2075);
FORCEPROP 2 LAST SEC_TYPE PIP
J 0
(-725 2050);
DISPLAY 1.021277 (-725 2050);
PAINT ORANGE (-725 2050);
DISPLAY INVISIBLE (-725 2050);
FORCEPROP 2 LAST SEC 1
J 0
(-725 2050);
DISPLAY 0.680851 (-725 2050);
PAINT MONO (-725 2050);
DISPLAY INVISIBLE (-725 2050);
FORCEADD CAP_A..1
(-1125 4325);
FORCEPROP 1 LASTPIN (-1125 4225) $PN 2
J 0
(-1115 4205);
DISPLAY 0.617021 (-1115 4205);
PAINT ORANGE (-1115 4205);
FORCEPROP 1 LASTPIN (-1125 4425) $PN 1
J 0
(-1115 4405);
DISPLAY 0.617021 (-1115 4405);
PAINT ORANGE (-1115 4405);
FORCEPROP 1 LAST MATERIAL X7R
J 0
(-1075 4225);
DISPLAY 0.617021 (-1075 4225);
PAINT SKYBLUE (-1075 4225);
FORCEPROP 1 LAST VOLTAGE 16V
J 0
(-1075 4325);
DISPLAY 0.617021 (-1075 4325);
PAINT SKYBLUE (-1075 4325);
FORCEPROP 1 LAST PACK_TYPE 0402V
J 0
(-1075 4125);
DISPLAY 0.617021 (-1075 4125);
PAINT SKYBLUE (-1075 4125);
FORCEPROP 1 LAST TOLERANCE 10%
J 0
(-1075 4275);
DISPLAY 0.617021 (-1075 4275);
PAINT SKYBLUE (-1075 4275);
FORCEPROP 1 LAST VALUE 0.1UF
J 0
(-1075 4375);
DISPLAY 0.617021 (-1075 4375);
PAINT SKYBLUE (-1075 4375);
FORCEPROP 1 LAST PART_NUMBER A36096-030
J 0
(-1075 4175);
DISPLAY 0.617021 (-1075 4175);
PAINT BLUE (-1075 4175);
FORCEPROP 1 LAST LOCATION C1E20
J 0
(-1075 4425);
DISPLAY 0.617021 (-1075 4425);
PAINT AQUA (-1075 4425);
FORCEPROP 2 LAST CDS_LIB dev_discrete
J 0
(-1125 4325);
PAINT ORANGE (-1125 4325);
DISPLAY INVISIBLE (-1125 4325);
FORCEPROP 2 LAST SEC_TYPE 0402V
J 0
(-1075 4525);
DISPLAY 1.021277 (-1075 4525);
PAINT ORANGE (-1075 4525);
DISPLAY INVISIBLE (-1075 4525);
FORCEPROP 0 LAST ROOM CPU_FANS
J 0
(-1075 4525);
DISPLAY 1.021277 (-1075 4525);
PAINT ORANGE (-1075 4525);
DISPLAY INVISIBLE (-1075 4525);
FORCEPROP 2 LAST CDS_LOCATION C1E20
J 0
(-1075 4425);
DISPLAY 0.617021 (-1075 4425);
PAINT AQUA (-1075 4425);
DISPLAY INVISIBLE (-1075 4425);
FORCEPROP 2 LAST SEC 1
J 0
(-1075 4525);
DISPLAY 0.680851 (-1075 4525);
PAINT MONO (-1075 4525);
DISPLAY INVISIBLE (-1075 4525);
FORCEPROP 0 LAST BOM_COST SM_THERM
J 0
(-1075 4475);
DISPLAY 1.021277 (-1075 4475);
PAINT ORANGE (-1075 4475);
DISPLAY INVISIBLE (-1075 4475);
FORCEPROP 1 LAST PATH I4
J 0
(-1075 4475);
DISPLAY 0.978723 (-1075 4475);
PAINT WHITE (-1075 4475);
DISPLAY INVISIBLE (-1075 4475);
FORCEPROP 2 LAST CDS_SEC 1
J 0
(-1075 4475);
PAINT ORANGE (-1075 4475);
DISPLAY INVISIBLE (-1075 4475);
FORCEADD DIODE..1
(-1675 3825);
FORCEPROP 1 LAST MATERIAL IC
J 0
(-1700 3647);
DISPLAY 0.617021 (-1700 3647);
PAINT SKYBLUE (-1700 3647);
FORCEPROP 1 LAST PACK_TYPE SM
J 0
(-1700 3585);
DISPLAY 0.617021 (-1700 3585);
PAINT SKYBLUE (-1700 3585);
FORCEPROP 1 LASTPIN (-1575 3825) $PN 1
J 0
(-1610 3835);
DISPLAY 0.617021 (-1610 3835);
PAINT AQUA (-1610 3835);
FORCEPROP 1 LASTPIN (-1775 3825) $PN 2
J 2
(-1740 3835);
DISPLAY 0.617021 (-1740 3835);
PAINT AQUA (-1740 3835);
FORCEPROP 1 LAST LOCATION CR1F1
J 0
(-1752 3981);
DISPLAY 0.617021 (-1752 3981);
PAINT AQUA (-1752 3981);
FORCEPROP 1 LAST VALUE SDMK0340L
J 0
(-1700 3700);
DISPLAY 0.617021 (-1700 3700);
PAINT SKYBLUE (-1700 3700);
FORCEPROP 1 LAST PART_NUMBER H71799-001
J 0
(-1700 3925);
DISPLAY 0.617021 (-1700 3925);
PAINT BLUE (-1700 3925);
FORCEPROP 2 LAST CDS_LIB mstr_discrete
J 0
(-1675 3825);
PAINT ORANGE (-1675 3825);
DISPLAY INVISIBLE (-1675 3825);
FORCEPROP 2 LAST CDS_LOCATION CR1F1
J 0
(-1752 3981);
DISPLAY 0.617021 (-1752 3981);
PAINT AQUA (-1752 3981);
DISPLAY INVISIBLE (-1752 3981);
FORCEPROP 1 LAST PATH I42
J 0
(-1695 4035);
DISPLAY 0.978723 (-1695 4035);
PAINT PINK (-1695 4035);
DISPLAY INVISIBLE (-1695 4035);
FORCEPROP 0 LAST ROOM CPU_FANS
J 0
(-1700 4075);
DISPLAY 1.021277 (-1700 4075);
PAINT ORANGE (-1700 4075);
DISPLAY INVISIBLE (-1700 4075);
FORCEPROP 2 LAST SEC 1
J 0
(-1675 4100);
DISPLAY 0.680851 (-1675 4100);
PAINT MONO (-1675 4100);
DISPLAY INVISIBLE (-1675 4100);
FORCEPROP 2 LAST SEC_TYPE SM
J 0
(-1675 4100);
DISPLAY 1.021277 (-1675 4100);
PAINT ORANGE (-1675 4100);
DISPLAY INVISIBLE (-1675 4100);
FORCEPROP 0 LAST BOM_COST SM_THERM
J 0
(-1700 4175);
DISPLAY 1.021277 (-1700 4175);
PAINT ORANGE (-1700 4175);
DISPLAY INVISIBLE (-1700 4175);
FORCEADD RES..1
(-2525 3825);
FORCEPROP 1 LASTPIN (-2625 3825) $PN 1
J 0
(-2613 3837);
DISPLAY 0.617021 (-2613 3837);
PAINT ORANGE (-2613 3837);
FORCEPROP 1 LAST WATTAGE 1/16W
J 2
(-2550 3675);
DISPLAY 0.617021 (-2550 3675);
PAINT SKYBLUE (-2550 3675);
FORCEPROP 1 LAST VALUE 100.0
J 2
(-2550 3725);
DISPLAY 0.617021 (-2550 3725);
PAINT SKYBLUE (-2550 3725);
FORCEPROP 1 LAST PART_NUMBER G21796-017
J 0
(-2575 3925);
DISPLAY 0.617021 (-2575 3925);
PAINT BLUE (-2575 3925);
FORCEPROP 1 LAST LOCATION R1F2
J 0
(-2575 3875);
DISPLAY 0.617021 (-2575 3875);
PAINT AQUA (-2575 3875);
FORCEPROP 1 LASTPIN (-2425 3825) $PN 2
J 0
(-2463 3837);
DISPLAY 0.617021 (-2463 3837);
PAINT ORANGE (-2463 3837);
FORCEPROP 1 LAST TOLERANCE 1%
J 0
(-2525 3725);
DISPLAY 0.617021 (-2525 3725);
PAINT SKYBLUE (-2525 3725);
FORCEPROP 1 LAST PACK_TYPE 0402
J 0
(-2425 3725);
DISPLAY 0.617021 (-2425 3725);
PAINT SKYBLUE (-2425 3725);
FORCEPROP 1 LAST MATERIAL CHIP
J 0
(-2525 3675);
DISPLAY 0.617021 (-2525 3675);
PAINT SKYBLUE (-2525 3675);
FORCEPROP 2 LAST SEC_TYPE 0402
J 0
(-2575 4025);
DISPLAY 1.021277 (-2575 4025);
PAINT ORANGE (-2575 4025);
DISPLAY INVISIBLE (-2575 4025);
FORCEPROP 2 LAST SEC 1
J 0
(-2575 4025);
DISPLAY 0.680851 (-2575 4025);
PAINT MONO (-2575 4025);
DISPLAY INVISIBLE (-2575 4025);
FORCEPROP 2 LAST CDS_LOCATION R1F2
J 0
(-2575 3875);
DISPLAY 0.617021 (-2575 3875);
PAINT AQUA (-2575 3875);
DISPLAY INVISIBLE (-2575 3875);
FORCEPROP 2 LAST NO_XNET_CONNECTION 1
J 0
(-2575 4025);
PAINT MONO (-2575 4025);
DISPLAY INVISIBLE (-2575 4025);
FORCEPROP 1 LAST PATH I43
J 0
(-2575 3975);
DISPLAY 0.978723 (-2575 3975);
PAINT WHITE (-2575 3975);
DISPLAY INVISIBLE (-2575 3975);
FORCEPROP 0 LAST ROOM CPU_FANS
J 0
(-2575 4025);
DISPLAY 1.021277 (-2575 4025);
PAINT ORANGE (-2575 4025);
DISPLAY INVISIBLE (-2575 4025);
FORCEPROP 2 LAST CDS_LIB mstr_discrete
J 0
(-2525 3825);
PAINT ORANGE (-2525 3825);
DISPLAY INVISIBLE (-2525 3825);
FORCEPROP 0 LAST BOM_COST SM_THERM
J 0
(-2575 4125);
DISPLAY 1.021277 (-2575 4125);
PAINT ORANGE (-2575 4125);
DISPLAY INVISIBLE (-2575 4125);
FORCEADD RES..2
(-2900 4025);
FORCEPROP 1 LASTPIN (-2900 3925) $PN 2
J 0
(-2895 3935);
DISPLAY 0.617021 (-2895 3935);
PAINT ORANGE (-2895 3935);
FORCEPROP 1 LAST WATTAGE 1/16W
J 0
(-2860 4000);
DISPLAY 0.617021 (-2860 4000);
PAINT SKYBLUE (-2860 4000);
FORCEPROP 1 LAST MATERIAL CHIP
J 0
(-2860 3950);
DISPLAY 0.617021 (-2860 3950);
PAINT SKYBLUE (-2860 3950);
FORCEPROP 1 LAST PACK_TYPE 0402
J 0
(-2860 3850);
DISPLAY 0.617021 (-2860 3850);
PAINT SKYBLUE (-2860 3850);
FORCEPROP 1 LAST TOLERANCE 1%
J 0
(-2855 4050);
DISPLAY 0.617021 (-2855 4050);
PAINT SKYBLUE (-2855 4050);
FORCEPROP 1 LAST PART_NUMBER G21796-072
J 0
(-2860 3900);
DISPLAY 0.617021 (-2860 3900);
PAINT BLUE (-2860 3900);
FORCEPROP 1 LASTPIN (-2900 4125) $PN 1
J 0
(-2895 4087);
DISPLAY 0.617021 (-2895 4087);
PAINT ORANGE (-2895 4087);
FORCEPROP 1 LAST VALUE 4.75K
J 0
(-2855 4100);
DISPLAY 0.617021 (-2855 4100);
PAINT SKYBLUE (-2855 4100);
FORCEPROP 1 LAST LOCATION R1F1
J 0
(-2855 4150);
DISPLAY 0.617021 (-2855 4150);
PAINT AQUA (-2855 4150);
FORCEPROP 2 LAST CDS_LIB mstr_discrete
J 0
(-2900 4025);
PAINT ORANGE (-2900 4025);
DISPLAY INVISIBLE (-2900 4025);
FORCEPROP 2 LAST CDS_LOCATION R1F1
J 0
(-2855 4150);
DISPLAY 0.617021 (-2855 4150);
PAINT AQUA (-2855 4150);
DISPLAY INVISIBLE (-2855 4150);
FORCEPROP 1 LAST PATH I45
J 0
(-2850 4200);
DISPLAY 0.978723 (-2850 4200);
PAINT WHITE (-2850 4200);
DISPLAY INVISIBLE (-2850 4200);
FORCEPROP 0 LAST ROOM CPU_FANS
J 0
(-2850 4250);
DISPLAY 1.021277 (-2850 4250);
PAINT ORANGE (-2850 4250);
DISPLAY INVISIBLE (-2850 4250);
FORCEPROP 2 LAST SEC 1
J 0
(-2850 4250);
DISPLAY 0.680851 (-2850 4250);
PAINT MONO (-2850 4250);
DISPLAY INVISIBLE (-2850 4250);
FORCEPROP 2 LAST SEC_TYPE 0402
J 0
(-2850 4250);
DISPLAY 1.021277 (-2850 4250);
PAINT ORANGE (-2850 4250);
DISPLAY INVISIBLE (-2850 4250);
FORCEPROP 0 LAST BOM_COST SM_THERM
J 0
(-2850 4350);
DISPLAY 1.021277 (-2850 4350);
PAINT ORANGE (-2850 4350);
DISPLAY INVISIBLE (-2850 4350);
FORCEADD CAP_A..1
R 2
(-2775 3625);
FORCEPROP 1 LAST PART_NUMBER A36096-045
J 2
(-2825 3475);
DISPLAY 0.617021 (-2825 3475);
PAINT BLUE (-2825 3475);
FORCEPROP 1 LAST MATERIAL X7R
J 2
(-2825 3525);
DISPLAY 0.617021 (-2825 3525);
PAINT SKYBLUE (-2825 3525);
FORCEPROP 1 LAST PACK_TYPE 0402V
J 2
(-2825 3425);
DISPLAY 0.617021 (-2825 3425);
PAINT SKYBLUE (-2825 3425);
FORCEPROP 1 LASTPIN (-2775 3525) $PN 2
J 2
(-2785 3505);
DISPLAY 0.617021 (-2785 3505);
PAINT ORANGE (-2785 3505);
FORCEPROP 1 LAST TOLERANCE 10%
J 2
(-2825 3575);
DISPLAY 0.617021 (-2825 3575);
PAINT SKYBLUE (-2825 3575);
FORCEPROP 1 LAST VOLTAGE 25V
J 2
(-2825 3625);
DISPLAY 0.617021 (-2825 3625);
PAINT SKYBLUE (-2825 3625);
FORCEPROP 1 LAST VALUE 0.01UF
J 2
(-2825 3675);
DISPLAY 0.617021 (-2825 3675);
PAINT SKYBLUE (-2825 3675);
FORCEPROP 1 LAST LOCATION C1F9
J 2
(-2825 3725);
DISPLAY 0.617021 (-2825 3725);
PAINT AQUA (-2825 3725);
FORCEPROP 1 LASTPIN (-2775 3725) $PN 1
J 2
(-2785 3705);
DISPLAY 0.617021 (-2785 3705);
PAINT ORANGE (-2785 3705);
FORCEPROP 2 LAST CDS_SEC 1
J 0
(-2825 3775);
PAINT ORANGE (-2825 3775);
DISPLAY INVISIBLE (-2825 3775);
FORCEPROP 1 LAST PATH I46
J 2
(-2825 3775);
DISPLAY 0.978723 (-2825 3775);
PAINT WHITE (-2825 3775);
DISPLAY INVISIBLE (-2825 3775);
FORCEPROP 2 LAST CDS_LOCATION C1F9
J 2
(-2825 3725);
DISPLAY 0.617021 (-2825 3725);
PAINT AQUA (-2825 3725);
DISPLAY INVISIBLE (-2825 3725);
FORCEPROP 0 LAST BOM_COST SM_THERM
J 0
(-2825 3825);
DISPLAY 1.021277 (-2825 3825);
PAINT ORANGE (-2825 3825);
DISPLAY INVISIBLE (-2825 3825);
FORCEPROP 2 LAST SEC_TYPE 0402V
J 2
(-2825 3825);
DISPLAY 1.021277 (-2825 3825);
PAINT ORANGE (-2825 3825);
DISPLAY INVISIBLE (-2825 3825);
FORCEPROP 2 LAST SEC 1
J 2
(-2825 3825);
DISPLAY 0.680851 (-2825 3825);
PAINT MONO (-2825 3825);
DISPLAY INVISIBLE (-2825 3825);
FORCEPROP 0 LAST ROOM CPU_FANS
J 0
(-2825 3825);
DISPLAY 1.021277 (-2825 3825);
PAINT ORANGE (-2825 3825);
DISPLAY INVISIBLE (-2825 3825);
FORCEPROP 2 LAST CDS_LIB dev_discrete
J 0
(-2775 3625);
PAINT ORANGE (-2775 3625);
DISPLAY INVISIBLE (-2775 3625);
FORCEADD GND..1
(-2775 3375);
FORCEPROP 3 LASTPIN (-2775 3425) SIG_NAME GND\g
J 0
(-2765 3435);
DISPLAY 0.659574 (-2765 3435);
PAINT MONO (-2765 3435);
DISPLAY INVISIBLE (-2765 3435);
FORCEPROP 1 LAST VOLTAGE 0.0V
J 0
(-2820 3332);
DISPLAY 0.340426 (-2820 3332);
PAINT SKYBLUE (-2820 3332);
DISPLAY INVISIBLE (-2820 3332);
FORCEPROP 1 LAST BODY_TYPE PLUMBING
J 0
(-2820 3332);
DISPLAY 0.340426 (-2820 3332);
PAINT GREEN (-2820 3332);
DISPLAY INVISIBLE (-2820 3332);
FORCEPROP 1 LAST SIZE 1B
J 0
(-2700 3325);
DISPLAY 1.170213 (-2700 3325);
PAINT AQUA (-2700 3325);
DISPLAY INVISIBLE (-2700 3325);
FORCEPROP 1 LAST HDL_POWER GND
J 0
(-2775 3525);
DISPLAY 1.170213 (-2775 3525);
PAINT GREEN (-2775 3525);
DISPLAY INVISIBLE (-2775 3525);
FORCEPROP 1 LAST PATH I47
J 0
(-2700 3375);
DISPLAY 0.872340 (-2700 3375);
PAINT AQUA (-2700 3375);
DISPLAY INVISIBLE (-2700 3375);
FORCEPROP 2 LAST CDS_LIB mstr_symbols
J 0
(-2775 3375);
PAINT ORANGE (-2775 3375);
DISPLAY INVISIBLE (-2775 3375);
FORCEADD P3V3_STBY..1
(-2900 4250);
FORCEPROP 3 LASTPIN (-2900 4200) SIG_NAME P3V3_STBY\g
J 0
(-2890 4210);
DISPLAY 0.659574 (-2890 4210);
PAINT MONO (-2890 4210);
DISPLAY INVISIBLE (-2890 4210);
FORCEPROP 1 LAST HDL_POWER P3V3_STBY
J 0
(-3200 4125);
DISPLAY 0.872340 (-3200 4125);
PAINT ORANGE (-3200 4125);
DISPLAY INVISIBLE (-3200 4125);
FORCEPROP 1 LAST BODY_TYPE PLUMBING
J 0
(-2945 4207);
DISPLAY 0.340426 (-2945 4207);
PAINT GREEN (-2945 4207);
DISPLAY INVISIBLE (-2945 4207);
FORCEPROP 1 LAST VOLTAGE 3.3V
J 0
(-2945 4207);
DISPLAY 0.340426 (-2945 4207);
PAINT SKYBLUE (-2945 4207);
DISPLAY INVISIBLE (-2945 4207);
FORCEPROP 2 LAST CDS_LIB mstr_symbols
J 0
(-2900 4250);
PAINT ORANGE (-2900 4250);
DISPLAY INVISIBLE (-2900 4250);
FORCEPROP 1 LAST SIZE 1B
J 0
(-2855 4272);
DISPLAY 0.340426 (-2855 4272);
PAINT GREEN (-2855 4272);
DISPLAY INVISIBLE (-2855 4272);
FORCEPROP 1 LAST PATH I48
J 0
(-2855 4252);
DISPLAY 0.340426 (-2855 4252);
PAINT GREEN (-2855 4252);
DISPLAY INVISIBLE (-2855 4252);
FORCEADD OFFPAGE..2
R 2
(-3650 3825);
FORCEPROP 2 LAST $XR0 181 
J 0
(-3905 3825);
DISPLAY 0.638298 (-3905 3825);
PAINT MONO (-3905 3825);
FORCEPROP 2 LAST $XR1 120 
J 0
(-4025 3825);
DISPLAY 0.638298 (-4025 3825);
PAINT MONO (-4025 3825);
FORCEPROP 2 LAST $XR2 147 
J 0
(-4145 3825);
DISPLAY 0.638298 (-4145 3825);
PAINT MONO (-4145 3825);
FORCEPROP 1 LAST OFFPAGE TRUE
J 2
(-3975 3700);
DISPLAY 0.872340 (-3975 3700);
PAINT GREEN (-3975 3700);
DISPLAY INVISIBLE (-3975 3700);
FORCEPROP 1 LAST COMMENT_BODY TRUE
J 2
(-3605 3730);
DISPLAY 0.872340 (-3605 3730);
PAINT GREEN (-3605 3730);
DISPLAY INVISIBLE (-3605 3730);
FORCEPROP 2 LAST CDS_LIB mstr_standard
J 2
(-3650 3825);
PAINT ORANGE (-3650 3825);
DISPLAY INVISIBLE (-3650 3825);
FORCEPROP 2 LAST PATH I49
J 2
(-3700 3900);
DISPLAY 1.021277 (-3700 3900);
PAINT ORANGE (-3700 3900);
DISPLAY INVISIBLE (-3700 3900);
FORCEADD DIODE..4
(-1950 3325);
FORCEPROP 1 LASTPIN (-1950 3225) $PN 2
J 0
(-1935 3225);
DISPLAY 0.617021 (-1935 3225);
PAINT AQUA (-1935 3225);
FORCEPROP 1 LASTPIN (-1950 3425) $PN 1
J 0
(-1935 3395);
DISPLAY 0.617021 (-1935 3395);
PAINT AQUA (-1935 3395);
FORCEPROP 1 LAST PACK_TYPE SM
J 0
(-1849 3198);
DISPLAY 0.617021 (-1849 3198);
PAINT SKYBLUE (-1849 3198);
FORCEPROP 1 LAST VALUE SDMK0340L
J 0
(-1850 3375);
DISPLAY 0.617021 (-1850 3375);
PAINT SKYBLUE (-1850 3375);
FORCEPROP 1 LAST PART_NUMBER H71799-001
J 0
(-1850 3250);
DISPLAY 0.617021 (-1850 3250);
PAINT BLUE (-1850 3250);
FORCEPROP 1 LAST LOCATION CR1E1
J 0
(-1850 3430);
DISPLAY 0.617021 (-1850 3430);
PAINT AQUA (-1850 3430);
FORCEPROP 1 LAST MATERIAL EMPTY
J 0
(-1848 3309);
DISPLAY 0.617021 (-1848 3309);
PAINT RED (-1848 3309);
FORCEPROP 2 LAST CDS_LIB mstr_discrete
J 0
(-1950 3325);
PAINT ORANGE (-1950 3325);
DISPLAY INVISIBLE (-1950 3325);
FORCEPROP 0 LAST ROOM CPU_FANS
J 0
(-1850 3525);
DISPLAY 1.021277 (-1850 3525);
PAINT ORANGE (-1850 3525);
DISPLAY INVISIBLE (-1850 3525);
FORCEPROP 1 LAST PATH I50
J 0
(-1845 3490);
DISPLAY 0.978723 (-1845 3490);
PAINT PINK (-1845 3490);
DISPLAY INVISIBLE (-1845 3490);
FORCEPROP 2 LAST CDS_LOCATION CR1E1
J 0
(-1850 3430);
DISPLAY 0.617021 (-1850 3430);
PAINT AQUA (-1850 3430);
DISPLAY INVISIBLE (-1850 3430);
FORCEPROP 2 LAST SEC 1
J 0
(-1825 3550);
DISPLAY 0.680851 (-1825 3550);
PAINT MONO (-1825 3550);
DISPLAY INVISIBLE (-1825 3550);
FORCEPROP 2 LAST SEC_TYPE SM
J 0
(-1825 3550);
DISPLAY 1.021277 (-1825 3550);
PAINT ORANGE (-1825 3550);
DISPLAY INVISIBLE (-1825 3550);
FORCEPROP 0 LAST BOM_COST SM_THERM
J 0
(-1850 3625);
DISPLAY 1.021277 (-1850 3625);
PAINT ORANGE (-1850 3625);
DISPLAY INVISIBLE (-1850 3625);
FORCEADD RES..2
R 2
(-2175 3400);
FORCEPROP 1 LAST WATTAGE 1/16W
J 2
(-2215 3375);
DISPLAY 0.617021 (-2215 3375);
PAINT SKYBLUE (-2215 3375);
FORCEPROP 1 LAST MATERIAL CHIP
J 2
(-2215 3325);
DISPLAY 0.617021 (-2215 3325);
PAINT SKYBLUE (-2215 3325);
FORCEPROP 1 LAST PACK_TYPE 0402
J 2
(-2215 3225);
DISPLAY 0.617021 (-2215 3225);
PAINT SKYBLUE (-2215 3225);
FORCEPROP 1 LAST VALUE 4.75K
J 2
(-2220 3475);
DISPLAY 0.617021 (-2220 3475);
PAINT SKYBLUE (-2220 3475);
FORCEPROP 1 LAST PART_NUMBER G21796-072
J 2
(-2215 3275);
DISPLAY 0.617021 (-2215 3275);
PAINT BLUE (-2215 3275);
FORCEPROP 1 LAST LOCATION R1E12
J 2
(-2220 3525);
DISPLAY 0.617021 (-2220 3525);
PAINT AQUA (-2220 3525);
FORCEPROP 1 LASTPIN (-2175 3300) $PN 2
J 2
(-2180 3310);
DISPLAY 0.617021 (-2180 3310);
PAINT ORANGE (-2180 3310);
FORCEPROP 1 LASTPIN (-2175 3500) $PN 1
J 2
(-2180 3462);
DISPLAY 0.617021 (-2180 3462);
PAINT ORANGE (-2180 3462);
FORCEPROP 1 LAST TOLERANCE 1%
J 2
(-2220 3425);
DISPLAY 0.617021 (-2220 3425);
PAINT SKYBLUE (-2220 3425);
FORCEPROP 2 LAST CDS_LOCATION R1E12
J 2
(-2220 3525);
DISPLAY 0.617021 (-2220 3525);
PAINT AQUA (-2220 3525);
DISPLAY INVISIBLE (-2220 3525);
FORCEPROP 2 LAST CDS_LIB mstr_discrete
J 0
(-2175 3400);
PAINT MONO (-2175 3400);
DISPLAY INVISIBLE (-2175 3400);
FORCEPROP 1 LAST PATH I51
J 2
(-2225 3575);
DISPLAY 0.978723 (-2225 3575);
PAINT WHITE (-2225 3575);
DISPLAY INVISIBLE (-2225 3575);
FORCEPROP 2 LAST SEC_TYPE 0402
J 0
(-2225 3625);
DISPLAY 1.021277 (-2225 3625);
PAINT ORANGE (-2225 3625);
DISPLAY INVISIBLE (-2225 3625);
FORCEPROP 0 LAST BOM_COST SM_THERM
J 0
(-2200 3725);
DISPLAY 1.021277 (-2200 3725);
PAINT ORANGE (-2200 3725);
DISPLAY INVISIBLE (-2200 3725);
FORCEPROP 2 LAST SEC 1
J 0
(-2225 3625);
PAINT MONO (-2225 3625);
DISPLAY INVISIBLE (-2225 3625);
FORCEPROP 0 LAST ROOM CPU_FANS
J 0
(-2200 3625);
DISPLAY 1.021277 (-2200 3625);
PAINT ORANGE (-2200 3625);
DISPLAY INVISIBLE (-2200 3625);
FORCEADD P5V_STBY..1
(-1950 3625);
FORCEPROP 3 LASTPIN (-1950 3575) SIG_NAME P5V_STBY\g
J 0
(-1940 3585);
DISPLAY 0.659574 (-1940 3585);
PAINT MONO (-1940 3585);
DISPLAY INVISIBLE (-1940 3585);
FORCEPROP 1 LAST HDL_POWER P5V_STBY
J 0
(-2250 3500);
DISPLAY 0.872340 (-2250 3500);
PAINT ORANGE (-2250 3500);
DISPLAY INVISIBLE (-2250 3500);
FORCEPROP 1 LAST BODY_TYPE PLUMBING
J 0
(-1995 3582);
DISPLAY 0.340426 (-1995 3582);
PAINT GREEN (-1995 3582);
DISPLAY INVISIBLE (-1995 3582);
FORCEPROP 1 LAST VOLTAGE 5.0V
J 0
(-1995 3582);
DISPLAY 0.340426 (-1995 3582);
PAINT SKYBLUE (-1995 3582);
DISPLAY INVISIBLE (-1995 3582);
FORCEPROP 1 LAST SIZE 1B
J 0
(-1905 3647);
DISPLAY 0.340426 (-1905 3647);
PAINT GREEN (-1905 3647);
DISPLAY INVISIBLE (-1905 3647);
FORCEPROP 2 LAST CDS_LIB mstr_symbols
J 0
(-1950 3625);
PAINT ORANGE (-1950 3625);
DISPLAY INVISIBLE (-1950 3625);
FORCEPROP 1 LAST PATH I52
J 0
(-1905 3627);
DISPLAY 0.340426 (-1905 3627);
PAINT GREEN (-1905 3627);
DISPLAY INVISIBLE (-1905 3627);
FORCEADD OFFPAGE..1
(-3625 3225);
FORCEPROP 2 LAST $XR0 161 
J 0
(-3877 3225);
DISPLAY 0.638298 (-3877 3225);
PAINT MONO (-3877 3225);
FORCEPROP 2 LAST $XR1 181 
J 0
(-3997 3225);
DISPLAY 0.638298 (-3997 3225);
PAINT MONO (-3997 3225);
FORCEPROP 2 LAST CDS_LIB mstr_standard
J 0
(-3625 3225);
PAINT ORANGE (-3625 3225);
DISPLAY INVISIBLE (-3625 3225);
FORCEPROP 2 LAST PATH I53
J 0
(-3575 3300);
DISPLAY 1.021277 (-3575 3300);
PAINT ORANGE (-3575 3300);
DISPLAY INVISIBLE (-3575 3300);
FORCEPROP 1 LAST COMMENT_BODY TRUE
J 0
(-3500 3125);
DISPLAY 1.170213 (-3500 3125);
PAINT PEACH (-3500 3125);
DISPLAY INVISIBLE (-3500 3125);
FORCEPROP 1 LAST OFFPAGE TRUE
J 0
(-3300 3100);
DISPLAY 1.170213 (-3300 3100);
PAINT GREEN (-3300 3100);
DISPLAY INVISIBLE (-3300 3100);
FORCEADD P3V3_STBY..1
(-3050 2175);
FORCEPROP 3 LASTPIN (-3050 2125) SIG_NAME P3V3_STBY\g
J 0
(-3040 2135);
DISPLAY 0.659574 (-3040 2135);
PAINT MONO (-3040 2135);
DISPLAY INVISIBLE (-3040 2135);
FORCEPROP 1 LAST HDL_POWER P3V3_STBY
J 0
(-3350 2050);
DISPLAY 0.872340 (-3350 2050);
PAINT ORANGE (-3350 2050);
DISPLAY INVISIBLE (-3350 2050);
FORCEPROP 1 LAST BODY_TYPE PLUMBING
J 0
(-3095 2132);
DISPLAY 0.340426 (-3095 2132);
PAINT GREEN (-3095 2132);
DISPLAY INVISIBLE (-3095 2132);
FORCEPROP 1 LAST VOLTAGE 3.3V
J 0
(-3095 2132);
DISPLAY 0.340426 (-3095 2132);
PAINT SKYBLUE (-3095 2132);
DISPLAY INVISIBLE (-3095 2132);
FORCEPROP 2 LAST CDS_LIB mstr_symbols
J 0
(-3050 2175);
PAINT ORANGE (-3050 2175);
DISPLAY INVISIBLE (-3050 2175);
FORCEPROP 1 LAST PATH I61
J 0
(-3005 2177);
DISPLAY 0.340426 (-3005 2177);
PAINT GREEN (-3005 2177);
DISPLAY INVISIBLE (-3005 2177);
FORCEPROP 1 LAST SIZE 1B
J 0
(-3005 2197);
DISPLAY 0.340426 (-3005 2197);
PAINT GREEN (-3005 2197);
DISPLAY INVISIBLE (-3005 2197);
FORCEADD DIODE..1
(-1825 1750);
FORCEPROP 1 LAST PACK_TYPE SM
J 0
(-1850 1510);
DISPLAY 0.617021 (-1850 1510);
PAINT SKYBLUE (-1850 1510);
FORCEPROP 1 LASTPIN (-1925 1750) $PN 2
J 2
(-1890 1760);
DISPLAY 0.617021 (-1890 1760);
PAINT AQUA (-1890 1760);
FORCEPROP 1 LAST MATERIAL IC
J 0
(-1850 1572);
DISPLAY 0.617021 (-1850 1572);
PAINT SKYBLUE (-1850 1572);
FORCEPROP 1 LAST VALUE SDMK0340L
J 0
(-1850 1625);
DISPLAY 0.617021 (-1850 1625);
PAINT SKYBLUE (-1850 1625);
FORCEPROP 1 LAST PART_NUMBER H71799-001
J 0
(-1850 1850);
DISPLAY 0.617021 (-1850 1850);
PAINT BLUE (-1850 1850);
FORCEPROP 1 LAST LOCATION CR1B2
J 0
(-1852 1906);
DISPLAY 0.617021 (-1852 1906);
PAINT AQUA (-1852 1906);
FORCEPROP 1 LASTPIN (-1725 1750) $PN 1
J 0
(-1760 1760);
DISPLAY 0.617021 (-1760 1760);
PAINT AQUA (-1760 1760);
FORCEPROP 2 LAST CDS_LIB mstr_discrete
J 0
(-1825 1750);
PAINT ORANGE (-1825 1750);
DISPLAY INVISIBLE (-1825 1750);
FORCEPROP 2 LAST CDS_LOCATION CR1B2
J 0
(-1852 1906);
DISPLAY 0.617021 (-1852 1906);
PAINT AQUA (-1852 1906);
DISPLAY INVISIBLE (-1852 1906);
FORCEPROP 1 LAST PATH I62
J 0
(-1845 1960);
DISPLAY 0.978723 (-1845 1960);
PAINT PINK (-1845 1960);
DISPLAY INVISIBLE (-1845 1960);
FORCEPROP 0 LAST ROOM CPU_FANS
J 0
(-1850 2000);
DISPLAY 1.021277 (-1850 2000);
PAINT ORANGE (-1850 2000);
DISPLAY INVISIBLE (-1850 2000);
FORCEPROP 2 LAST SEC 1
J 0
(-1825 2025);
DISPLAY 0.680851 (-1825 2025);
PAINT MONO (-1825 2025);
DISPLAY INVISIBLE (-1825 2025);
FORCEPROP 2 LAST SEC_TYPE SM
J 0
(-1825 2025);
DISPLAY 1.021277 (-1825 2025);
PAINT ORANGE (-1825 2025);
DISPLAY INVISIBLE (-1825 2025);
FORCEPROP 0 LAST BOM_COST SM_THERM
J 0
(-1850 2100);
DISPLAY 1.021277 (-1850 2100);
PAINT ORANGE (-1850 2100);
DISPLAY INVISIBLE (-1850 2100);
FORCEADD P5V_STBY..1
(-2100 1550);
FORCEPROP 3 LASTPIN (-2100 1500) SIG_NAME P5V_STBY\g
J 0
(-2090 1510);
DISPLAY 0.659574 (-2090 1510);
PAINT MONO (-2090 1510);
DISPLAY INVISIBLE (-2090 1510);
FORCEPROP 1 LAST HDL_POWER P5V_STBY
J 0
(-2400 1425);
DISPLAY 0.872340 (-2400 1425);
PAINT ORANGE (-2400 1425);
DISPLAY INVISIBLE (-2400 1425);
FORCEPROP 1 LAST BODY_TYPE PLUMBING
J 0
(-2145 1507);
DISPLAY 0.340426 (-2145 1507);
PAINT GREEN (-2145 1507);
DISPLAY INVISIBLE (-2145 1507);
FORCEPROP 1 LAST VOLTAGE 5.0V
J 0
(-2145 1507);
DISPLAY 0.340426 (-2145 1507);
PAINT SKYBLUE (-2145 1507);
DISPLAY INVISIBLE (-2145 1507);
FORCEPROP 1 LAST PATH I63
J 0
(-2055 1552);
DISPLAY 0.340426 (-2055 1552);
PAINT GREEN (-2055 1552);
DISPLAY INVISIBLE (-2055 1552);
FORCEPROP 2 LAST CDS_LIB mstr_symbols
J 0
(-2100 1550);
PAINT ORANGE (-2100 1550);
DISPLAY INVISIBLE (-2100 1550);
FORCEPROP 1 LAST SIZE 1B
J 0
(-2055 1572);
DISPLAY 0.340426 (-2055 1572);
PAINT GREEN (-2055 1572);
DISPLAY INVISIBLE (-2055 1572);
FORCEADD DIODE..4
(-2100 1250);
FORCEPROP 1 LASTPIN (-2100 1150) $PN 2
J 0
(-2085 1150);
DISPLAY 0.617021 (-2085 1150);
PAINT AQUA (-2085 1150);
FORCEPROP 1 LASTPIN (-2100 1350) $PN 1
J 0
(-2085 1320);
DISPLAY 0.617021 (-2085 1320);
PAINT AQUA (-2085 1320);
FORCEPROP 1 LAST PACK_TYPE SM
J 0
(-1999 1123);
DISPLAY 0.617021 (-1999 1123);
PAINT SKYBLUE (-1999 1123);
FORCEPROP 1 LAST MATERIAL EMPTY
J 0
(-1998 1234);
DISPLAY 0.617021 (-1998 1234);
PAINT RED (-1998 1234);
FORCEPROP 1 LAST LOCATION CR1B1
J 0
(-2000 1355);
DISPLAY 0.617021 (-2000 1355);
PAINT AQUA (-2000 1355);
FORCEPROP 1 LAST VALUE SDMK0340L
J 0
(-2000 1300);
DISPLAY 0.617021 (-2000 1300);
PAINT SKYBLUE (-2000 1300);
FORCEPROP 1 LAST PART_NUMBER H71799-001
J 0
(-2000 1175);
DISPLAY 0.617021 (-2000 1175);
PAINT BLUE (-2000 1175);
FORCEPROP 2 LAST CDS_LIB mstr_discrete
J 0
(-2100 1250);
PAINT ORANGE (-2100 1250);
DISPLAY INVISIBLE (-2100 1250);
FORCEPROP 0 LAST ROOM CPU_FANS
J 0
(-2000 1450);
DISPLAY 1.021277 (-2000 1450);
PAINT ORANGE (-2000 1450);
DISPLAY INVISIBLE (-2000 1450);
FORCEPROP 1 LAST PATH I64
J 0
(-1995 1415);
DISPLAY 0.978723 (-1995 1415);
PAINT PINK (-1995 1415);
DISPLAY INVISIBLE (-1995 1415);
FORCEPROP 2 LAST CDS_LOCATION CR1B1
J 0
(-2000 1355);
DISPLAY 0.617021 (-2000 1355);
PAINT AQUA (-2000 1355);
DISPLAY INVISIBLE (-2000 1355);
FORCEPROP 2 LAST SEC 1
J 0
(-1975 1475);
DISPLAY 0.680851 (-1975 1475);
PAINT MONO (-1975 1475);
DISPLAY INVISIBLE (-1975 1475);
FORCEPROP 2 LAST SEC_TYPE SM
J 0
(-1975 1475);
DISPLAY 1.021277 (-1975 1475);
PAINT ORANGE (-1975 1475);
DISPLAY INVISIBLE (-1975 1475);
FORCEPROP 0 LAST BOM_COST SM_THERM
J 0
(-2000 1550);
DISPLAY 1.021277 (-2000 1550);
PAINT ORANGE (-2000 1550);
DISPLAY INVISIBLE (-2000 1550);
FORCEADD RES..2
R 2
(-2325 1300);
FORCEPROP 1 LAST PART_NUMBER G21796-072
J 2
(-2365 1175);
DISPLAY 0.617021 (-2365 1175);
PAINT BLUE (-2365 1175);
FORCEPROP 1 LAST MATERIAL CHIP
J 2
(-2365 1225);
DISPLAY 0.617021 (-2365 1225);
PAINT SKYBLUE (-2365 1225);
FORCEPROP 1 LAST PACK_TYPE 0402
J 2
(-2365 1125);
DISPLAY 0.617021 (-2365 1125);
PAINT SKYBLUE (-2365 1125);
FORCEPROP 1 LASTPIN (-2325 1200) $PN 2
J 2
(-2330 1210);
DISPLAY 0.617021 (-2330 1210);
PAINT ORANGE (-2330 1210);
FORCEPROP 1 LAST WATTAGE 1/16W
J 2
(-2365 1275);
DISPLAY 0.617021 (-2365 1275);
PAINT SKYBLUE (-2365 1275);
FORCEPROP 1 LAST VALUE 4.75K
J 2
(-2370 1375);
DISPLAY 0.617021 (-2370 1375);
PAINT SKYBLUE (-2370 1375);
FORCEPROP 1 LAST LOCATION R7F33
J 2
(-2370 1425);
DISPLAY 0.617021 (-2370 1425);
PAINT AQUA (-2370 1425);
FORCEPROP 1 LASTPIN (-2325 1400) $PN 1
J 2
(-2330 1362);
DISPLAY 0.617021 (-2330 1362);
PAINT ORANGE (-2330 1362);
FORCEPROP 1 LAST TOLERANCE 1%
J 2
(-2370 1325);
DISPLAY 0.617021 (-2370 1325);
PAINT SKYBLUE (-2370 1325);
FORCEPROP 2 LAST CDS_LIB mstr_discrete
J 0
(-2325 1300);
PAINT MONO (-2325 1300);
DISPLAY INVISIBLE (-2325 1300);
FORCEPROP 2 LAST CDS_LOCATION R7F33
J 2
(-2370 1425);
DISPLAY 0.617021 (-2370 1425);
PAINT AQUA (-2370 1425);
DISPLAY INVISIBLE (-2370 1425);
FORCEPROP 1 LAST PATH I65
J 2
(-2375 1475);
DISPLAY 0.978723 (-2375 1475);
PAINT WHITE (-2375 1475);
DISPLAY INVISIBLE (-2375 1475);
FORCEPROP 0 LAST ROOM CPU_FANS
J 0
(-2350 1525);
DISPLAY 1.021277 (-2350 1525);
PAINT ORANGE (-2350 1525);
DISPLAY INVISIBLE (-2350 1525);
FORCEPROP 2 LAST SEC 1
J 0
(-2375 1525);
PAINT MONO (-2375 1525);
DISPLAY INVISIBLE (-2375 1525);
FORCEPROP 2 LAST SEC_TYPE 0402
J 0
(-2375 1525);
DISPLAY 1.021277 (-2375 1525);
PAINT ORANGE (-2375 1525);
DISPLAY INVISIBLE (-2375 1525);
FORCEPROP 0 LAST BOM_COST SM_THERM
J 0
(-2350 1625);
DISPLAY 1.021277 (-2350 1625);
PAINT ORANGE (-2350 1625);
DISPLAY INVISIBLE (-2350 1625);
FORCEADD RES..1
(-2675 1750);
FORCEPROP 1 LAST WATTAGE 1/16W
J 2
(-2700 1600);
DISPLAY 0.617021 (-2700 1600);
PAINT SKYBLUE (-2700 1600);
FORCEPROP 1 LAST VALUE 100.0
J 2
(-2700 1650);
DISPLAY 0.617021 (-2700 1650);
PAINT SKYBLUE (-2700 1650);
FORCEPROP 1 LASTPIN (-2775 1750) $PN 1
J 0
(-2763 1762);
DISPLAY 0.617021 (-2763 1762);
PAINT ORANGE (-2763 1762);
FORCEPROP 1 LAST TOLERANCE 1%
J 0
(-2675 1650);
DISPLAY 0.617021 (-2675 1650);
PAINT SKYBLUE (-2675 1650);
FORCEPROP 1 LASTPIN (-2575 1750) $PN 2
J 0
(-2613 1762);
DISPLAY 0.617021 (-2613 1762);
PAINT ORANGE (-2613 1762);
FORCEPROP 1 LAST LOCATION R1B22
J 0
(-2725 1800);
DISPLAY 0.617021 (-2725 1800);
PAINT AQUA (-2725 1800);
FORCEPROP 1 LAST MATERIAL CHIP
J 0
(-2675 1600);
DISPLAY 0.617021 (-2675 1600);
PAINT SKYBLUE (-2675 1600);
FORCEPROP 1 LAST PACK_TYPE 0402
J 0
(-2575 1650);
DISPLAY 0.617021 (-2575 1650);
PAINT SKYBLUE (-2575 1650);
FORCEPROP 1 LAST PART_NUMBER G21796-017
J 0
(-2725 1850);
DISPLAY 0.617021 (-2725 1850);
PAINT BLUE (-2725 1850);
FORCEPROP 2 LAST CDS_LIB mstr_discrete
J 0
(-2675 1750);
PAINT ORANGE (-2675 1750);
DISPLAY INVISIBLE (-2675 1750);
FORCEPROP 0 LAST ROOM CPU_FANS
J 0
(-2725 1950);
DISPLAY 1.021277 (-2725 1950);
PAINT ORANGE (-2725 1950);
DISPLAY INVISIBLE (-2725 1950);
FORCEPROP 1 LAST PATH I67
J 0
(-2725 1900);
DISPLAY 0.978723 (-2725 1900);
PAINT WHITE (-2725 1900);
DISPLAY INVISIBLE (-2725 1900);
FORCEPROP 2 LAST NO_XNET_CONNECTION 1
J 0
(-2725 1950);
PAINT MONO (-2725 1950);
DISPLAY INVISIBLE (-2725 1950);
FORCEPROP 2 LAST SEC_TYPE 0402
J 0
(-2725 1950);
DISPLAY 1.021277 (-2725 1950);
PAINT ORANGE (-2725 1950);
DISPLAY INVISIBLE (-2725 1950);
FORCEPROP 2 LAST SEC 1
J 0
(-2725 1950);
DISPLAY 0.680851 (-2725 1950);
PAINT MONO (-2725 1950);
DISPLAY INVISIBLE (-2725 1950);
FORCEPROP 2 LAST CDS_LOCATION R1B22
J 0
(-2725 1800);
DISPLAY 0.617021 (-2725 1800);
PAINT AQUA (-2725 1800);
DISPLAY INVISIBLE (-2725 1800);
FORCEPROP 0 LAST BOM_COST SM_THERM
J 0
(-2725 2050);
DISPLAY 1.021277 (-2725 2050);
PAINT ORANGE (-2725 2050);
DISPLAY INVISIBLE (-2725 2050);
FORCEADD CAP_A..1
R 2
(-2925 1550);
FORCEPROP 1 LAST PACK_TYPE 0402V
J 2
(-2975 1350);
DISPLAY 0.617021 (-2975 1350);
PAINT SKYBLUE (-2975 1350);
FORCEPROP 1 LAST VALUE 0.01UF
J 2
(-2975 1600);
DISPLAY 0.617021 (-2975 1600);
PAINT SKYBLUE (-2975 1600);
FORCEPROP 1 LAST PART_NUMBER A36096-045
J 2
(-2975 1400);
DISPLAY 0.617021 (-2975 1400);
PAINT BLUE (-2975 1400);
FORCEPROP 1 LAST TOLERANCE 10%
J 2
(-2975 1500);
DISPLAY 0.617021 (-2975 1500);
PAINT SKYBLUE (-2975 1500);
FORCEPROP 1 LAST MATERIAL X7R
J 2
(-2975 1450);
DISPLAY 0.617021 (-2975 1450);
PAINT SKYBLUE (-2975 1450);
FORCEPROP 1 LASTPIN (-2925 1450) $PN 2
J 2
(-2935 1430);
DISPLAY 0.617021 (-2935 1430);
PAINT ORANGE (-2935 1430);
FORCEPROP 1 LAST VOLTAGE 25V
J 2
(-2975 1550);
DISPLAY 0.617021 (-2975 1550);
PAINT SKYBLUE (-2975 1550);
FORCEPROP 1 LASTPIN (-2925 1650) $PN 1
J 2
(-2935 1630);
DISPLAY 0.617021 (-2935 1630);
PAINT ORANGE (-2935 1630);
FORCEPROP 1 LAST LOCATION C1B15
J 2
(-2725 1550);
DISPLAY 0.617021 (-2725 1550);
PAINT AQUA (-2725 1550);
FORCEPROP 0 LAST BOM_COST SM_THERM
J 0
(-2975 1700);
DISPLAY 1.021277 (-2975 1700);
PAINT ORANGE (-2975 1700);
DISPLAY INVISIBLE (-2975 1700);
FORCEPROP 2 LAST CDS_SEC 1
J 0
(-2975 1650);
PAINT ORANGE (-2975 1650);
DISPLAY INVISIBLE (-2975 1650);
FORCEPROP 2 LAST SEC 1
J 2
(-2975 1750);
DISPLAY 0.680851 (-2975 1750);
PAINT MONO (-2975 1750);
DISPLAY INVISIBLE (-2975 1750);
FORCEPROP 1 LAST PATH I68
J 2
(-2975 1700);
DISPLAY 0.978723 (-2975 1700);
PAINT WHITE (-2975 1700);
DISPLAY INVISIBLE (-2975 1700);
FORCEPROP 0 LAST ROOM CPU_FANS
J 0
(-2975 1700);
DISPLAY 1.021277 (-2975 1700);
PAINT ORANGE (-2975 1700);
DISPLAY INVISIBLE (-2975 1700);
FORCEPROP 2 LAST CDS_LIB dev_discrete
J 0
(-2925 1550);
PAINT ORANGE (-2925 1550);
DISPLAY INVISIBLE (-2925 1550);
FORCEPROP 2 LAST SEC_TYPE 0402V
J 2
(-2975 1750);
DISPLAY 1.021277 (-2975 1750);
PAINT ORANGE (-2975 1750);
DISPLAY INVISIBLE (-2975 1750);
FORCEPROP 2 LAST CDS_LOCATION C1B15
J 2
(-2725 1550);
DISPLAY 0.617021 (-2725 1550);
PAINT AQUA (-2725 1550);
DISPLAY INVISIBLE (-2725 1550);
FORCEADD GND..1
(-2925 1300);
FORCEPROP 3 LASTPIN (-2925 1350) SIG_NAME GND\g
J 0
(-2915 1360);
DISPLAY 0.659574 (-2915 1360);
PAINT MONO (-2915 1360);
DISPLAY INVISIBLE (-2915 1360);
FORCEPROP 1 LAST BODY_TYPE PLUMBING
J 0
(-2970 1257);
DISPLAY 0.340426 (-2970 1257);
PAINT GREEN (-2970 1257);
DISPLAY INVISIBLE (-2970 1257);
FORCEPROP 1 LAST VOLTAGE 0.0V
J 0
(-2970 1257);
DISPLAY 0.340426 (-2970 1257);
PAINT SKYBLUE (-2970 1257);
DISPLAY INVISIBLE (-2970 1257);
FORCEPROP 1 LAST SIZE 1B
J 0
(-2850 1250);
DISPLAY 1.170213 (-2850 1250);
PAINT AQUA (-2850 1250);
DISPLAY INVISIBLE (-2850 1250);
FORCEPROP 2 LAST CDS_LIB mstr_symbols
J 0
(-2925 1300);
PAINT ORANGE (-2925 1300);
DISPLAY INVISIBLE (-2925 1300);
FORCEPROP 1 LAST PATH I69
J 0
(-2850 1300);
DISPLAY 0.872340 (-2850 1300);
PAINT AQUA (-2850 1300);
DISPLAY INVISIBLE (-2850 1300);
FORCEPROP 1 LAST HDL_POWER GND
J 0
(-2925 1450);
DISPLAY 1.170213 (-2925 1450);
PAINT GREEN (-2925 1450);
DISPLAY INVISIBLE (-2925 1450);
FORCEADD RES..2
(-3050 1950);
FORCEPROP 1 LAST PACK_TYPE 0402
J 0
(-3010 1775);
DISPLAY 0.617021 (-3010 1775);
PAINT SKYBLUE (-3010 1775);
FORCEPROP 1 LAST TOLERANCE 1%
J 0
(-3005 1975);
DISPLAY 0.617021 (-3005 1975);
PAINT SKYBLUE (-3005 1975);
FORCEPROP 1 LASTPIN (-3050 1850) $PN 2
J 0
(-3045 1860);
DISPLAY 0.617021 (-3045 1860);
PAINT ORANGE (-3045 1860);
FORCEPROP 1 LASTPIN (-3050 2050) $PN 1
J 0
(-3045 2012);
DISPLAY 0.617021 (-3045 2012);
PAINT ORANGE (-3045 2012);
FORCEPROP 1 LAST MATERIAL CHIP
J 0
(-3010 1875);
DISPLAY 0.617021 (-3010 1875);
PAINT SKYBLUE (-3010 1875);
FORCEPROP 1 LAST WATTAGE 1/16W
J 0
(-3010 1925);
DISPLAY 0.617021 (-3010 1925);
PAINT SKYBLUE (-3010 1925);
FORCEPROP 1 LAST PART_NUMBER G21796-072
J 0
(-3010 1825);
DISPLAY 0.617021 (-3010 1825);
PAINT BLUE (-3010 1825);
FORCEPROP 1 LAST VALUE 4.75K
J 0
(-3005 2025);
DISPLAY 0.617021 (-3005 2025);
PAINT SKYBLUE (-3005 2025);
FORCEPROP 1 LAST LOCATION R1B21
J 0
(-3005 2075);
DISPLAY 0.617021 (-3005 2075);
PAINT AQUA (-3005 2075);
FORCEPROP 2 LAST CDS_LIB mstr_discrete
J 0
(-3050 1950);
PAINT ORANGE (-3050 1950);
DISPLAY INVISIBLE (-3050 1950);
FORCEPROP 1 LAST PATH I70
J 0
(-3000 2125);
DISPLAY 0.978723 (-3000 2125);
PAINT WHITE (-3000 2125);
DISPLAY INVISIBLE (-3000 2125);
FORCEPROP 2 LAST CDS_LOCATION R1B21
J 0
(-3005 2075);
DISPLAY 0.617021 (-3005 2075);
PAINT AQUA (-3005 2075);
DISPLAY INVISIBLE (-3005 2075);
FORCEPROP 0 LAST ROOM CPU_FANS
J 0
(-3000 2175);
DISPLAY 1.021277 (-3000 2175);
PAINT ORANGE (-3000 2175);
DISPLAY INVISIBLE (-3000 2175);
FORCEPROP 2 LAST SEC 1
J 0
(-3000 2175);
DISPLAY 0.680851 (-3000 2175);
PAINT MONO (-3000 2175);
DISPLAY INVISIBLE (-3000 2175);
FORCEPROP 2 LAST SEC_TYPE 0402
J 0
(-3000 2175);
DISPLAY 1.021277 (-3000 2175);
PAINT ORANGE (-3000 2175);
DISPLAY INVISIBLE (-3000 2175);
FORCEPROP 0 LAST BOM_COST SM_THERM
J 0
(-3000 2275);
DISPLAY 1.021277 (-3000 2275);
PAINT ORANGE (-3000 2275);
DISPLAY INVISIBLE (-3000 2275);
FORCEADD OFFPAGE..2
R 2
(-3600 1750);
FORCEPROP 2 LAST $XR0 181 
J 0
(-3885 1750);
DISPLAY 0.638298 (-3885 1750);
PAINT MONO (-3885 1750);
FORCEPROP 2 LAST $XR1 120 
J 0
(-4005 1750);
DISPLAY 0.638298 (-4005 1750);
PAINT MONO (-4005 1750);
FORCEPROP 2 LAST $XR2 147 
J 0
(-4125 1750);
DISPLAY 0.638298 (-4125 1750);
PAINT MONO (-4125 1750);
FORCEPROP 1 LAST OFFPAGE TRUE
J 2
(-3925 1625);
DISPLAY 0.872340 (-3925 1625);
PAINT GREEN (-3925 1625);
DISPLAY INVISIBLE (-3925 1625);
FORCEPROP 2 LAST CDS_LIB mstr_standard
J 2
(-3600 1750);
PAINT ORANGE (-3600 1750);
DISPLAY INVISIBLE (-3600 1750);
FORCEPROP 2 LAST PATH I75
J 0
(-3550 1825);
DISPLAY 1.021277 (-3550 1825);
PAINT ORANGE (-3550 1825);
DISPLAY INVISIBLE (-3550 1825);
FORCEPROP 1 LAST COMMENT_BODY TRUE
J 2
(-3555 1655);
DISPLAY 0.872340 (-3555 1655);
PAINT GREEN (-3555 1655);
DISPLAY INVISIBLE (-3555 1655);
FORCEADD OFFPAGE..1
(-3600 1125);
FORCEPROP 2 LAST $XR0 161 
J 0
(-3852 1125);
DISPLAY 0.638298 (-3852 1125);
PAINT MONO (-3852 1125);
FORCEPROP 1 LAST OFFPAGE TRUE
J 0
(-3275 1000);
DISPLAY 1.170213 (-3275 1000);
PAINT GREEN (-3275 1000);
DISPLAY INVISIBLE (-3275 1000);
FORCEPROP 2 LAST CDS_LIB mstr_standard
J 0
(-3600 1125);
PAINT ORANGE (-3600 1125);
DISPLAY INVISIBLE (-3600 1125);
FORCEPROP 2 LAST PATH I76
J 0
(-3550 1200);
DISPLAY 1.021277 (-3550 1200);
PAINT ORANGE (-3550 1200);
DISPLAY INVISIBLE (-3550 1200);
FORCEPROP 1 LAST COMMENT_BODY TRUE
J 0
(-3475 1025);
DISPLAY 1.170213 (-3475 1025);
PAINT PEACH (-3475 1025);
DISPLAY INVISIBLE (-3475 1025);
FORCEADD TTL1G07_A..1
(-6350 3850);
FORCEPROP 2 LASTPIN (-6450 3850) $PN 2
J 2
(-6460 3860);
DISPLAY 0.617021 (-6460 3860);
PAINT ORANGE (-6460 3860);
FORCEPROP 1 LAST VALUE 74LVC1G07
J 1
(-6350 3950);
DISPLAY 0.617021 (-6350 3950);
PAINT SKYBLUE (-6350 3950);
FORCEPROP 1 LAST LOCATION U8G2
J 0
(-6450 4000);
DISPLAY 0.617021 (-6450 4000);
PAINT AQUA (-6450 4000);
FORCEPROP 1 LAST MATERIAL IC
J 0
(-6325 4000);
DISPLAY 0.617021 (-6325 4000);
PAINT SKYBLUE (-6325 4000);
FORCEPROP 2 LASTPIN (-6200 3850) $PN 4
J 0
(-6190 3860);
DISPLAY 0.617021 (-6190 3860);
PAINT ORANGE (-6190 3860);
FORCEPROP 1 LAST PART_NUMBER C88419-001
J 0
(-6400 3715);
DISPLAY 0.617021 (-6400 3715);
PAINT BLUE (-6400 3715);
FORCEPROP 1 LAST POWER_GROUP VCC=P3V3_STBY;GND=GND
J 1
(-6400 3660);
DISPLAY 0.617021 (-6400 3660);
PAINT ORANGE (-6400 3660);
FORCEPROP 2 LAST CDS_LOCATION U8G2
J 0
(-6450 4000);
DISPLAY 0.617021 (-6450 4000);
PAINT AQUA (-6450 4000);
DISPLAY INVISIBLE (-6450 4000);
FORCEPROP 2 LAST CDS_LIB mstr_ttl
J 0
(-6350 3850);
PAINT ORANGE (-6350 3850);
DISPLAY INVISIBLE (-6350 3850);
FORCEPROP 1 LAST PATH I88
J 0
(-6300 3900);
DISPLAY 0.978723 (-6300 3900);
PAINT WHITE (-6300 3900);
DISPLAY INVISIBLE (-6300 3900);
FORCEPROP 0 LAST ROOM CPU_FANS
J 0
(-6400 4150);
DISPLAY 1.021277 (-6400 4150);
PAINT ORANGE (-6400 4150);
DISPLAY INVISIBLE (-6400 4150);
FORCEPROP 2 LAST SEC 1
J 0
(-6400 4100);
DISPLAY 0.680851 (-6400 4100);
PAINT MONO (-6400 4100);
DISPLAY INVISIBLE (-6400 4100);
FORCEPROP 2 LAST SEC_TYPE SOP
J 0
(-6400 4100);
DISPLAY 1.021277 (-6400 4100);
PAINT ORANGE (-6400 4100);
DISPLAY INVISIBLE (-6400 4100);
FORCEPROP 0 LAST BOM_COST SM_THERM
J 0
(-6400 4250);
DISPLAY 1.021277 (-6400 4250);
PAINT ORANGE (-6400 4250);
DISPLAY INVISIBLE (-6400 4250);
FORCEPROP 1 LAST PACK_TYPE SOP
J 0
(-6400 4100);
DISPLAY 0.978723 (-6400 4100);
PAINT SKYBLUE (-6400 4100);
DISPLAY INVISIBLE (-6400 4100);
FORCEADD CAP_A..1
(-6300 4450);
FORCEPROP 1 LASTPIN (-6300 4350) $PN 2
J 0
(-6290 4330);
DISPLAY 0.617021 (-6290 4330);
PAINT ORANGE (-6290 4330);
FORCEPROP 1 LAST MATERIAL X7R
J 0
(-6250 4350);
DISPLAY 0.617021 (-6250 4350);
PAINT SKYBLUE (-6250 4350);
FORCEPROP 1 LASTPIN (-6300 4550) $PN 1
J 0
(-6290 4530);
DISPLAY 0.617021 (-6290 4530);
PAINT ORANGE (-6290 4530);
FORCEPROP 1 LAST VOLTAGE 16V
J 0
(-6250 4450);
DISPLAY 0.617021 (-6250 4450);
PAINT SKYBLUE (-6250 4450);
FORCEPROP 1 LAST TOLERANCE 10%
J 0
(-6250 4400);
DISPLAY 0.617021 (-6250 4400);
PAINT SKYBLUE (-6250 4400);
FORCEPROP 1 LAST PACK_TYPE 0402V
J 0
(-6250 4250);
DISPLAY 0.617021 (-6250 4250);
PAINT SKYBLUE (-6250 4250);
FORCEPROP 1 LAST VALUE 0.1UF
J 0
(-6250 4500);
DISPLAY 0.617021 (-6250 4500);
PAINT SKYBLUE (-6250 4500);
FORCEPROP 1 LAST PART_NUMBER A36096-030
J 0
(-6250 4300);
DISPLAY 0.617021 (-6250 4300);
PAINT BLUE (-6250 4300);
FORCEPROP 1 LAST LOCATION C2U27
J 0
(-6250 4550);
DISPLAY 0.617021 (-6250 4550);
PAINT AQUA (-6250 4550);
FORCEPROP 2 LAST CDS_LIB dev_discrete
J 0
(-6300 4450);
PAINT ORANGE (-6300 4450);
DISPLAY INVISIBLE (-6300 4450);
FORCEPROP 2 LAST CDS_LOCATION C2U27
J 0
(-6250 4550);
DISPLAY 0.617021 (-6250 4550);
PAINT AQUA (-6250 4550);
DISPLAY INVISIBLE (-6250 4550);
FORCEPROP 2 LAST CDS_SEC 1
J 0
(-6250 4600);
PAINT ORANGE (-6250 4600);
DISPLAY INVISIBLE (-6250 4600);
FORCEPROP 1 LAST PATH I90
J 0
(-6250 4600);
DISPLAY 0.978723 (-6250 4600);
PAINT WHITE (-6250 4600);
DISPLAY INVISIBLE (-6250 4600);
FORCEPROP 2 LAST SEC 1
J 0
(-6250 4650);
DISPLAY 0.680851 (-6250 4650);
PAINT MONO (-6250 4650);
DISPLAY INVISIBLE (-6250 4650);
FORCEPROP 2 LAST SEC_TYPE 0402V
J 0
(-6250 4650);
DISPLAY 1.021277 (-6250 4650);
PAINT ORANGE (-6250 4650);
DISPLAY INVISIBLE (-6250 4650);
FORCEPROP 0 LAST BOM_COST SM_THERM
J 0
(-6250 4750);
DISPLAY 1.021277 (-6250 4750);
PAINT ORANGE (-6250 4750);
DISPLAY INVISIBLE (-6250 4750);
FORCEPROP 0 LAST ROOM CPU_FANS
J 0
(-6250 4650);
DISPLAY 1.021277 (-6250 4650);
PAINT ORANGE (-6250 4650);
DISPLAY INVISIBLE (-6250 4650);
FORCEADD TTL1G07_A..1
(-6425 1100);
FORCEPROP 1 LAST POWER_GROUP VCC=P3V3_STBY;GND=GND
J 1
(-6800 1010);
DISPLAY 0.617021 (-6800 1010);
PAINT ORANGE (-6800 1010);
FORCEPROP 2 LASTPIN (-6525 1100) $PN 2
J 2
(-6535 1110);
DISPLAY 0.617021 (-6535 1110);
PAINT ORANGE (-6535 1110);
FORCEPROP 1 LAST LOCATION U8G3
J 0
(-6525 1250);
DISPLAY 0.617021 (-6525 1250);
PAINT AQUA (-6525 1250);
FORCEPROP 1 LAST VALUE 74LVC1G07
J 1
(-6425 1200);
DISPLAY 0.617021 (-6425 1200);
PAINT SKYBLUE (-6425 1200);
FORCEPROP 2 LASTPIN (-6275 1100) $PN 4
J 0
(-6265 1110);
DISPLAY 0.617021 (-6265 1110);
PAINT ORANGE (-6265 1110);
FORCEPROP 1 LAST MATERIAL IC
J 0
(-6375 1250);
DISPLAY 0.617021 (-6375 1250);
PAINT SKYBLUE (-6375 1250);
FORCEPROP 1 LAST PART_NUMBER C88419-001
J 0
(-6300 1165);
DISPLAY 0.617021 (-6300 1165);
PAINT BLUE (-6300 1165);
FORCEPROP 1 LAST PACK_TYPE SOP
J 0
(-6475 1350);
DISPLAY 0.978723 (-6475 1350);
PAINT SKYBLUE (-6475 1350);
DISPLAY INVISIBLE (-6475 1350);
FORCEPROP 2 LAST CDS_LIB mstr_ttl
J 0
(-6425 1100);
PAINT ORANGE (-6425 1100);
DISPLAY INVISIBLE (-6425 1100);
FORCEPROP 2 LAST SEC_TYPE SOP
J 0
(-6475 1350);
DISPLAY 1.021277 (-6475 1350);
PAINT ORANGE (-6475 1350);
DISPLAY INVISIBLE (-6475 1350);
FORCEPROP 2 LAST SEC 1
J 0
(-6475 1350);
DISPLAY 0.680851 (-6475 1350);
PAINT MONO (-6475 1350);
DISPLAY INVISIBLE (-6475 1350);
FORCEPROP 2 LAST CDS_LOCATION U8G3
J 0
(-6525 1250);
DISPLAY 0.617021 (-6525 1250);
PAINT AQUA (-6525 1250);
DISPLAY INVISIBLE (-6525 1250);
FORCEPROP 0 LAST ROOM CPU_FANS
J 0
(-6475 1400);
DISPLAY 1.021277 (-6475 1400);
PAINT ORANGE (-6475 1400);
DISPLAY INVISIBLE (-6475 1400);
FORCEPROP 1 LAST PATH I92
J 0
(-6375 1150);
DISPLAY 0.978723 (-6375 1150);
PAINT WHITE (-6375 1150);
DISPLAY INVISIBLE (-6375 1150);
FORCEPROP 0 LAST BOM_COST SM_THERM
J 0
(-6475 1500);
DISPLAY 1.021277 (-6475 1500);
PAINT ORANGE (-6475 1500);
DISPLAY INVISIBLE (-6475 1500);
FORCEADD CAP_A..1
(-6200 675);
FORCEPROP 1 LASTPIN (-6200 575) $PN 2
J 0
(-6190 555);
DISPLAY 0.617021 (-6190 555);
PAINT ORANGE (-6190 555);
FORCEPROP 1 LASTPIN (-6200 775) $PN 1
J 0
(-6190 755);
DISPLAY 0.617021 (-6190 755);
PAINT ORANGE (-6190 755);
FORCEPROP 1 LAST MATERIAL X7R
J 0
(-6150 575);
DISPLAY 0.617021 (-6150 575);
PAINT SKYBLUE (-6150 575);
FORCEPROP 1 LAST VOLTAGE 16V
J 0
(-6150 675);
DISPLAY 0.617021 (-6150 675);
PAINT SKYBLUE (-6150 675);
FORCEPROP 1 LAST PACK_TYPE 0402V
J 0
(-6150 475);
DISPLAY 0.617021 (-6150 475);
PAINT SKYBLUE (-6150 475);
FORCEPROP 1 LAST TOLERANCE 10%
J 0
(-6150 625);
DISPLAY 0.617021 (-6150 625);
PAINT SKYBLUE (-6150 625);
FORCEPROP 1 LAST VALUE 0.1UF
J 0
(-6150 725);
DISPLAY 0.617021 (-6150 725);
PAINT SKYBLUE (-6150 725);
FORCEPROP 1 LAST PART_NUMBER A36096-030
J 0
(-6150 525);
DISPLAY 0.617021 (-6150 525);
PAINT BLUE (-6150 525);
FORCEPROP 1 LAST LOCATION C2U28
J 0
(-6150 775);
DISPLAY 0.617021 (-6150 775);
PAINT AQUA (-6150 775);
FORCEPROP 2 LAST CDS_LIB dev_discrete
J 0
(-6200 675);
PAINT ORANGE (-6200 675);
DISPLAY INVISIBLE (-6200 675);
FORCEPROP 1 LAST PATH I93
J 0
(-6150 825);
DISPLAY 0.978723 (-6150 825);
PAINT WHITE (-6150 825);
DISPLAY INVISIBLE (-6150 825);
FORCEPROP 2 LAST CDS_LOCATION C2U28
J 0
(-6150 775);
DISPLAY 0.617021 (-6150 775);
PAINT AQUA (-6150 775);
DISPLAY INVISIBLE (-6150 775);
FORCEPROP 2 LAST CDS_SEC 1
J 0
(-6150 825);
PAINT ORANGE (-6150 825);
DISPLAY INVISIBLE (-6150 825);
FORCEPROP 2 LAST SEC 1
J 0
(-6150 875);
DISPLAY 0.680851 (-6150 875);
PAINT MONO (-6150 875);
DISPLAY INVISIBLE (-6150 875);
FORCEPROP 2 LAST SEC_TYPE 0402V
J 0
(-6150 875);
DISPLAY 1.021277 (-6150 875);
PAINT ORANGE (-6150 875);
DISPLAY INVISIBLE (-6150 875);
FORCEPROP 0 LAST ROOM CPU_FANS
J 0
(-6150 875);
DISPLAY 1.021277 (-6150 875);
PAINT ORANGE (-6150 875);
DISPLAY INVISIBLE (-6150 875);
FORCEPROP 0 LAST BOM_COST SM_THERM
J 0
(-6150 975);
DISPLAY 1.021277 (-6150 975);
PAINT ORANGE (-6150 975);
DISPLAY INVISIBLE (-6150 975);
FORCEADD OFFPAGE..1
(-7250 3850);
FORCEPROP 2 LAST $XR0 120 
J 0
(-7502 3850);
DISPLAY 0.638298 (-7502 3850);
PAINT MONO (-7502 3850);
FORCEPROP 2 LAST $XR1 147 
J 0
(-7622 3850);
DISPLAY 0.638298 (-7622 3850);
PAINT MONO (-7622 3850);
FORCEPROP 2 LAST PATH I94
J 0
(-7200 3925);
DISPLAY 1.021277 (-7200 3925);
PAINT ORANGE (-7200 3925);
DISPLAY INVISIBLE (-7200 3925);
FORCEPROP 2 LAST CDS_LIB mstr_standard
J 0
(-7250 3850);
PAINT ORANGE (-7250 3850);
DISPLAY INVISIBLE (-7250 3850);
FORCEPROP 1 LAST OFFPAGE TRUE
J 0
(-6925 3725);
DISPLAY 1.170213 (-6925 3725);
PAINT GREEN (-6925 3725);
DISPLAY INVISIBLE (-6925 3725);
FORCEPROP 1 LAST COMMENT_BODY TRUE
J 0
(-7125 3750);
DISPLAY 1.170213 (-7125 3750);
PAINT PEACH (-7125 3750);
DISPLAY INVISIBLE (-7125 3750);
FORCEADD P3V3_STBY..1
(-6300 4650);
FORCEPROP 3 LASTPIN (-6300 4600) SIG_NAME P3V3_STBY\g
J 0
(-6290 4610);
DISPLAY 0.659574 (-6290 4610);
PAINT MONO (-6290 4610);
DISPLAY INVISIBLE (-6290 4610);
FORCEPROP 1 LAST HDL_POWER P3V3_STBY
J 0
(-6600 4525);
DISPLAY 0.872340 (-6600 4525);
PAINT ORANGE (-6600 4525);
DISPLAY INVISIBLE (-6600 4525);
FORCEPROP 1 LAST BODY_TYPE PLUMBING
J 0
(-6345 4607);
DISPLAY 0.340426 (-6345 4607);
PAINT GREEN (-6345 4607);
DISPLAY INVISIBLE (-6345 4607);
FORCEPROP 1 LAST VOLTAGE 3.3V
J 0
(-6345 4607);
DISPLAY 0.340426 (-6345 4607);
PAINT SKYBLUE (-6345 4607);
DISPLAY INVISIBLE (-6345 4607);
FORCEPROP 1 LAST PATH I96
J 0
(-6255 4652);
DISPLAY 0.340426 (-6255 4652);
PAINT GREEN (-6255 4652);
DISPLAY INVISIBLE (-6255 4652);
FORCEPROP 1 LAST SIZE 1B
J 0
(-6255 4672);
DISPLAY 0.340426 (-6255 4672);
PAINT GREEN (-6255 4672);
DISPLAY INVISIBLE (-6255 4672);
FORCEPROP 2 LAST CDS_LIB mstr_symbols
J 0
(-6300 4650);
PAINT ORANGE (-6300 4650);
DISPLAY INVISIBLE (-6300 4650);
FORCEADD GND..1
(-6300 4250);
FORCEPROP 3 LASTPIN (-6300 4300) SIG_NAME GND\g
J 0
(-6290 4310);
DISPLAY 0.659574 (-6290 4310);
PAINT MONO (-6290 4310);
DISPLAY INVISIBLE (-6290 4310);
FORCEPROP 1 LAST VOLTAGE 0.0V
J 0
(-6345 4207);
DISPLAY 0.340426 (-6345 4207);
PAINT SKYBLUE (-6345 4207);
DISPLAY INVISIBLE (-6345 4207);
FORCEPROP 2 LAST CDS_LIB mstr_symbols
J 0
(-6300 4250);
PAINT ORANGE (-6300 4250);
DISPLAY INVISIBLE (-6300 4250);
FORCEPROP 1 LAST BODY_TYPE PLUMBING
J 0
(-6345 4207);
DISPLAY 0.340426 (-6345 4207);
PAINT GREEN (-6345 4207);
DISPLAY INVISIBLE (-6345 4207);
FORCEPROP 1 LAST SIZE 1B
J 0
(-6225 4200);
DISPLAY 1.170213 (-6225 4200);
PAINT AQUA (-6225 4200);
DISPLAY INVISIBLE (-6225 4200);
FORCEPROP 1 LAST PATH I97
J 0
(-6225 4250);
DISPLAY 0.872340 (-6225 4250);
PAINT AQUA (-6225 4250);
DISPLAY INVISIBLE (-6225 4250);
FORCEPROP 1 LAST HDL_POWER GND
J 0
(-6300 4400);
DISPLAY 1.170213 (-6300 4400);
PAINT GREEN (-6300 4400);
DISPLAY INVISIBLE (-6300 4400);
FORCEADD OFFPAGE..2
(-4800 3850);
FORCEPROP 2 LAST $XR0 161 
J 0
(-4611 3850);
DISPLAY 0.638298 (-4611 3850);
PAINT MONO (-4611 3850);
FORCEPROP 2 LAST $XR1 181 
J 0
(-4491 3850);
DISPLAY 0.638298 (-4491 3850);
PAINT MONO (-4491 3850);
FORCEPROP 1 LAST COMMENT_BODY TRUE
J 0
(-4845 3755);
DISPLAY 0.872340 (-4845 3755);
PAINT GREEN (-4845 3755);
DISPLAY INVISIBLE (-4845 3755);
FORCEPROP 2 LAST PATH I98
J 2
(-4850 3925);
DISPLAY 1.021277 (-4850 3925);
PAINT ORANGE (-4850 3925);
DISPLAY INVISIBLE (-4850 3925);
FORCEPROP 2 LAST CDS_LIB mstr_standard
J 2
(-4800 3850);
PAINT ORANGE (-4800 3850);
DISPLAY INVISIBLE (-4800 3850);
FORCEPROP 1 LAST OFFPAGE TRUE
J 0
(-4475 3725);
DISPLAY 0.872340 (-4475 3725);
PAINT GREEN (-4475 3725);
DISPLAY INVISIBLE (-4475 3725);
FORCEADD RES..1
(-5450 3850);
FORCEPROP 1 LAST VALUE 221
J 2
(-5475 3750);
DISPLAY 0.617021 (-5475 3750);
PAINT SKYBLUE (-5475 3750);
FORCEPROP 1 LAST WATTAGE 1/16W
J 2
(-5475 3700);
DISPLAY 0.617021 (-5475 3700);
PAINT SKYBLUE (-5475 3700);
FORCEPROP 1 LASTPIN (-5550 3850) $PN 1
J 0
(-5538 3862);
DISPLAY 0.617021 (-5538 3862);
PAINT ORANGE (-5538 3862);
FORCEPROP 1 LASTPIN (-5350 3850) $PN 2
J 0
(-5388 3862);
DISPLAY 0.617021 (-5388 3862);
PAINT ORANGE (-5388 3862);
FORCEPROP 1 LAST MATERIAL CHIP
J 0
(-5450 3700);
DISPLAY 0.617021 (-5450 3700);
PAINT SKYBLUE (-5450 3700);
FORCEPROP 1 LAST LOCATION R2U42
J 0
(-5500 3900);
DISPLAY 0.617021 (-5500 3900);
PAINT AQUA (-5500 3900);
FORCEPROP 1 LAST PART_NUMBER G21796-271
J 0
(-5500 3950);
DISPLAY 0.617021 (-5500 3950);
PAINT BLUE (-5500 3950);
FORCEPROP 1 LAST TOLERANCE 1.0%
J 0
(-5450 3750);
DISPLAY 0.617021 (-5450 3750);
PAINT SKYBLUE (-5450 3750);
FORCEPROP 1 LAST PACK_TYPE 0402
J 0
(-5200 3700);
DISPLAY 0.617021 (-5200 3700);
PAINT SKYBLUE (-5200 3700);
FORCEPROP 2 LAST CDS_LOCATION R2U42
J 0
(-5500 3900);
DISPLAY 0.617021 (-5500 3900);
PAINT AQUA (-5500 3900);
DISPLAY INVISIBLE (-5500 3900);
FORCEPROP 2 LAST SEC 1
J 0
(-5500 4050);
DISPLAY 0.680851 (-5500 4050);
PAINT MONO (-5500 4050);
DISPLAY INVISIBLE (-5500 4050);
FORCEPROP 2 LAST CDS_LIB mstr_discrete
J 0
(-5450 3850);
PAINT ORANGE (-5450 3850);
DISPLAY INVISIBLE (-5450 3850);
FORCEPROP 2 LAST SEC_TYPE 0402
J 0
(-5500 4050);
DISPLAY 1.021277 (-5500 4050);
PAINT ORANGE (-5500 4050);
DISPLAY INVISIBLE (-5500 4050);
FORCEPROP 1 LAST PATH I99
J 0
(-5500 4000);
DISPLAY 0.978723 (-5500 4000);
PAINT WHITE (-5500 4000);
DISPLAY INVISIBLE (-5500 4000);
FORCEPROP 0 LAST ROOM CPU_FANS
J 0
(-5500 4050);
DISPLAY 1.021277 (-5500 4050);
PAINT ORANGE (-5500 4050);
DISPLAY INVISIBLE (-5500 4050);
FORCEPROP 0 LAST BOM_COST SM_THERM
J 0
(-5500 4150);
DISPLAY 1.021277 (-5500 4150);
PAINT ORANGE (-5500 4150);
DISPLAY INVISIBLE (-5500 4150);
FORCEADD CAD_NOTE..1
(-5825 4475);
FORCEPROP 0 LAST L1 PLACE CAP CLOSE
J 0
(-5975 4350);
DISPLAY 0.617021 (-5975 4350);
PAINT WHITE (-5975 4350);
FORCEPROP 0 LAST L2 TO IC
J 0
(-5975 4275);
DISPLAY 0.617021 (-5975 4275);
PAINT WHITE (-5975 4275);
FORCEPROP 1 LAST COMMENT_BODY TRUE
J 0
(-5800 4575);
DISPLAY 1.361702 (-5800 4575);
PAINT WHITE (-5800 4575);
DISPLAY INVISIBLE (-5800 4575);
FORCEPROP 2 LAST CDS_LIB mstr_symbols
J 0
(-5825 4475);
PAINT ORANGE (-5825 4475);
DISPLAY INVISIBLE (-5825 4475);
FORCEADD DNS..2
(-5945 2795);
PAINT RED (-5945 2795);
FORCEPROP 1 LAST COMMENT_BODY TRUE
R 1
J 0
(-5870 2570);
DISPLAY 0.872340 (-5870 2570);
PAINT GREEN (-5870 2570);
DISPLAY INVISIBLE (-5870 2570);
FORCEPROP 2 LAST CDS_LIB mstr_misc
J 0
(-5945 2795);
PAINT ORANGE (-5945 2795);
DISPLAY INVISIBLE (-5945 2795);
FORCEADD CAD_NOTE..1
(-5325 2225);
FORCEPROP 0 LAST L2 TO IC
J 0
(-5475 2025);
DISPLAY 0.617021 (-5475 2025);
PAINT WHITE (-5475 2025);
FORCEPROP 0 LAST L1 PLACE CAP CLOSE
J 0
(-5475 2100);
DISPLAY 0.617021 (-5475 2100);
PAINT WHITE (-5475 2100);
FORCEPROP 1 LAST COMMENT_BODY TRUE
J 0
(-5300 2325);
DISPLAY 1.361702 (-5300 2325);
PAINT WHITE (-5300 2325);
DISPLAY INVISIBLE (-5300 2325);
FORCEPROP 2 LAST CDS_LIB mstr_symbols
J 0
(-5325 2225);
PAINT ORANGE (-5325 2225);
DISPLAY INVISIBLE (-5325 2225);
FORCEADD DNS..2
(-1945 3320);
PAINT RED (-1945 3320);
FORCEPROP 1 LAST COMMENT_BODY TRUE
R 1
J 0
(-1870 3095);
DISPLAY 0.872340 (-1870 3095);
PAINT GREEN (-1870 3095);
DISPLAY INVISIBLE (-1870 3095);
FORCEPROP 2 LAST CDS_LIB mstr_misc
J 0
(-1945 3320);
PAINT ORANGE (-1945 3320);
DISPLAY INVISIBLE (-1945 3320);
FORCEADD CAD_NOTE..1
(-5725 700);
FORCEPROP 0 LAST L2 TO IC
J 0
(-5875 500);
DISPLAY 0.617021 (-5875 500);
PAINT WHITE (-5875 500);
FORCEPROP 0 LAST L1 PLACE CAP CLOSE
J 0
(-5875 575);
DISPLAY 0.617021 (-5875 575);
PAINT WHITE (-5875 575);
FORCEPROP 1 LAST COMMENT_BODY TRUE
J 0
(-5700 800);
DISPLAY 1.361702 (-5700 800);
PAINT WHITE (-5700 800);
DISPLAY INVISIBLE (-5700 800);
FORCEPROP 2 LAST CDS_LIB mstr_symbols
J 0
(-5725 700);
PAINT ORANGE (-5725 700);
DISPLAY INVISIBLE (-5725 700);
FORCEADD DNS..2
(-2095 1245);
PAINT RED (-2095 1245);
FORCEPROP 1 LAST COMMENT_BODY TRUE
R 1
J 0
(-2020 1020);
DISPLAY 0.872340 (-2020 1020);
PAINT GREEN (-2020 1020);
DISPLAY INVISIBLE (-2020 1020);
FORCEPROP 2 LAST CDS_LIB mstr_misc
J 0
(-2095 1245);
PAINT ORANGE (-2095 1245);
DISPLAY INVISIBLE (-2095 1245);
FORCEADD INTEL_CORP_BPAGE..1
(-25 25);
FORCEPROP 1 LAST CDS_CON_LAST_MODIFIED Tue Dec 01 11:52:10 2015
J 0
(-1450 350);
DISPLAY 1.361702 (-1450 350);
PAINT GREEN (-1450 350);
DISPLAY INVISIBLE (-1450 350);
FORCEPROP 1 LAST CUSTOM_TXT_CDS <CURRENT_DESIGN_SHEET> OF <TOTAL_DESIGN_SHEETS>
J 0
(-525 50);
PAINT GREEN (-525 50);
FORCEPROP 1 LAST CUSTOM_TXT_CDS <CON_LAST_MODIFIED>
J 0
(-1950 375);
PAINT GREEN (-1950 375);
FORCEPROP 2 LAST CUSTOM_TXT_CDS <XR_PAGE_TITLE>
J 0
(-7915 5275);
DISPLAY 0.638298 (-7915 5275);
PAINT PINK (-7915 5275);
DISPLAY INVISIBLE (-7915 5275);
FORCEPROP 1 LAST SCH_TITLE FAN HEADERS
J 0
(-7975 75);
DISPLAY 1.212766 (-7975 75);
PAINT ORANGE (-7975 75);
FORCEPROP 1 LAST SCH_ADDRESS2 P.O. BOX 58119
J 0
(-4000 100);
DISPLAY 0.617021 (-4000 100);
PAINT GREEN (-4000 100);
FORCEPROP 1 LAST SCH_ADDRESS1 2200 Mission College Blvd.
J 0
(-4000 150);
DISPLAY 0.617021 (-4000 150);
PAINT GREEN (-4000 150);
FORCEPROP 1 LAST SCH_ADDRESS3 Santa Clara, CA 95052-8119
J 0
(-4000 50);
DISPLAY 0.617021 (-4000 50);
PAINT GREEN (-4000 50);
FORCEPROP 1 LAST SCH_NUMBER H4694802
J 0
(-1325 175);
DISPLAY 1.212766 (-1325 175);
PAINT YELLOW (-1325 175);
FORCEPROP 1 LAST SCH_DEPT BESD
J 1
(-4475 125);
DISPLAY 1.212766 (-4475 125);
PAINT YELLOW (-4475 125);
FORCEPROP 1 LAST SCH_REV 2.420
J 0
(-275 175);
DISPLAY 0.978723 (-275 175);
PAINT YELLOW (-275 175);
FORCEPROP 2 LAST PAGE_BORDER TRUE
J 0
(-7915 5275);
DISPLAY 0.851064 (-7915 5275);
PAINT PINK (-7915 5275);
DISPLAY INVISIBLE (-7915 5275);
FORCEPROP 1 LAST COMMENT_BODY TRUE
J 0
(-13 37);
DISPLAY 0.617021 (-13 37);
PAINT GREEN (-13 37);
DISPLAY INVISIBLE (-13 37);
FORCEPROP 2 LAST CDS_LIB mstr_symbols
J 0
(-25 25);
DISPLAY 1.361702 (-25 25);
PAINT ORANGE (-25 25);
DISPLAY INVISIBLE (-25 25);
FORCEPROP 2 LAST CDS_XR_PAGE_TITLE CR-161 : @BASEBOARD_FAB2_LIB.BASEBOARD_FAB2(SCH_1):PAGE161
J 0
(-7915 5275);
DISPLAY 0.638298 (-7915 5275);
PAINT PINK (-7915 5275);
DISPLAY INVISIBLE (-7915 5275);
WIRE 16 -1 (-6200 575)(-6200 525);
WIRE 16 -1 (-6200 800)(-6200 775);
WIRE 16 -1 (-1000 2375)(-1000 2475);
WIRE 16 -1 (-1000 2475)(-1300 2475);
WIRE 16 -1 (-1375 2475)(-1300 2475);
WIRE 16 -1 (-1300 2475)(-1300 2375);
WIRE 16 -1 (-1375 1800)(-1375 2475);
WIRE 16 -1 (-1375 2525)(-1375 2475);
WIRE 16 -1 (-1375 1800)(-875 1800);
WIRE 16 -1 (-1125 4425)(-1125 4550);
WIRE 16 -1 (-1125 4550)(-1400 4550);
WIRE 16 -1 (-1400 4550)(-1400 4450);
WIRE 16 -1 (-1500 4550)(-1400 4550);
WIRE 16 -1 (-1500 3875)(-1500 4550);
WIRE 16 -1 (-1500 4675)(-1500 4550);
WIRE 16 -1 (-1500 3875)(-825 3875);
WIRE 16 -1 (-1150 1850)(-875 1850);
WIRE 16 -1 (-5775 2300)(-5775 2250);
WIRE 16 -1 (-5775 2050)(-5775 2000);
WIRE 16 -1 (-5950 2975)(-5950 2900);
WIRE 16 -1 (-1075 3925)(-825 3925);
WIRE 16 -1 (-3175 450)(-3175 425);
WIRE 16 -1 (-1125 4150)(-1400 4150);
WIRE 16 -1 (-1125 4225)(-1125 4150);
WIRE 16 -1 (-1125 4150)(-1125 4125);
WIRE 16 -1 (-1400 4150)(-1400 4250);
WIRE 16 -1 (-2925 925)(-2925 950);
WIRE 16 -1 (-3300 2525)(-3300 2450);
WIRE 16 -1 (-3225 3025)(-3225 3050);
WIRE 16 -1 (-1000 2175)(-1000 2075);
WIRE 16 -1 (-1300 2075)(-1000 2075);
WIRE 16 -1 (-1300 2075)(-1300 2175);
WIRE 16 -1 (-1300 2075)(-1300 2000);
WIRE 16 -1 (-2775 3525)(-2775 3425);
WIRE 16 -1 (-2900 4200)(-2900 4125);
WIRE 16 -1 (-1950 3575)(-1950 3500);
WIRE 16 -1 (-1950 3500)(-1950 3425);
WIRE 16 -1 (-2175 3500)(-1950 3500);
WIRE 16 -1 (-3050 2125)(-3050 2050);
WIRE 16 -1 (-2325 1400)(-2325 1425);
WIRE 16 -1 (-2325 1425)(-2100 1425);
WIRE 16 -1 (-2100 1500)(-2100 1425);
WIRE 16 -1 (-2100 1425)(-2100 1350);
WIRE 16 -1 (-2925 1450)(-2925 1350);
WIRE 16 -1 (-6300 4600)(-6300 4550);
WIRE 16 -1 (-6300 4350)(-6300 4300);
WIRE 16 -1 (-1450 3775)(-825 3775);
WIRE 16 -1 (-1450 3775)(-1450 3150);
WIRE 16 -1 (-1450 3150)(-1950 3150);
WIRE 16 -1 (-1950 3225)(-1950 3150);
WIRE 16 -1 (-1950 3150)(-2175 3150);
WIRE 16 -1 (-2175 3150)(-2175 3225);
WIRE 16 -1 (-2175 3300)(-2175 3225);
WIRE 16 -1 (-2175 3225)(-3575 3225);
FORCEPROP 0 LAST SIG_NAME FAN_PWM_OUT_SYS0_R
J 0
(-3560 3235);
DISPLAY 0.617021 (-3560 3235);
PAINT ORANGE (-3560 3235);
WIRE 16 -1 (-825 3725)(-1325 3725);
FORCEPROP 0 LAST SIG_NAME FAN_TACH1_CPU1_D1
J 0
(-1310 3725);
DISPLAY 0.617021 (-1310 3725);
PAINT ORANGE (-1310 3725);
FORCEPROP 2 LASTPROP $XRERR UNIQUE?
J 0
(-1550 3725);
DISPLAY 0.638298 (-1550 3725);
PAINT MONO (-1550 3725);
DISPLAY INVISIBLE (-1550 3725);
WIRE 16 -1 (-1325 3725)(-1325 2775);
WIRE 16 -1 (-1875 2775)(-1325 2775);
WIRE 16 -1 (-1575 3825)(-825 3825);
FORCEPROP 0 LAST SIG_NAME FAN_TACH0_CPU0_D1
J 0
(-1310 3835);
DISPLAY 0.617021 (-1310 3835);
PAINT ORANGE (-1310 3835);
FORCEPROP 2 LASTPROP $XRERR UNIQUE?
J 0
(-1550 3835);
DISPLAY 0.638298 (-1550 3835);
PAINT MONO (-1550 3835);
DISPLAY INVISIBLE (-1550 3835);
WIRE 16 -1 (-825 3675)(-1125 3675);
FORCEPROP 0 LAST SIG_NAME TP_FAN_0
J 0
(-1110 3675);
DISPLAY 0.617021 (-1110 3675);
PAINT ORANGE (-1110 3675);
FORCEPROP 2 LASTPROP $XRERR UNIQUE?
J 0
(-1365 3675);
DISPLAY 0.638298 (-1365 3675);
PAINT MONO (-1365 3675);
DISPLAY INVISIBLE (-1365 3675);
WIRE 16 -1 (-1600 1700)(-875 1700);
WIRE 16 -1 (-1600 1700)(-1600 1075);
WIRE 16 -1 (-1600 1075)(-2100 1075);
WIRE 16 -1 (-2100 1150)(-2100 1075);
WIRE 16 -1 (-2100 1075)(-2325 1075);
WIRE 16 -1 (-2325 1125)(-2325 1075);
WIRE 16 -1 (-2325 1200)(-2325 1125);
WIRE 16 -1 (-2325 1125)(-3550 1125);
FORCEPROP 0 LAST SIG_NAME FAN_PWM_OUT_SYS1_R
J 0
(-3535 1135);
DISPLAY 0.617021 (-3535 1135);
PAINT ORANGE (-3535 1135);
WIRE 16 -1 (-1500 1650)(-875 1650);
FORCEPROP 0 LAST SIG_NAME FAN_TACH3_CPU1_D1
J 0
(-1485 1650);
DISPLAY 0.617021 (-1485 1650);
PAINT ORANGE (-1485 1650);
FORCEPROP 2 LASTPROP $XRERR UNIQUE?
J 0
(-1725 1650);
DISPLAY 0.638298 (-1725 1650);
PAINT MONO (-1725 1650);
DISPLAY INVISIBLE (-1725 1650);
WIRE 16 -1 (-1500 675)(-1500 1650);
WIRE 16 -1 (-1675 675)(-1500 675);
WIRE 16 -1 (-1725 1750)(-875 1750);
FORCEPROP 0 LAST SIG_NAME FAN_TACH2_CPU1_D1
J 0
(-1485 1750);
DISPLAY 0.617021 (-1485 1750);
PAINT ORANGE (-1485 1750);
FORCEPROP 2 LASTPROP $XRERR UNIQUE?
J 0
(-1725 1750);
DISPLAY 0.638298 (-1725 1750);
PAINT MONO (-1725 1750);
DISPLAY INVISIBLE (-1725 1750);
WIRE 16 -1 (-875 1600)(-1175 1600);
FORCEPROP 0 LAST SIG_NAME TP_FAN_1
J 0
(-1185 1600);
DISPLAY 0.617021 (-1185 1600);
PAINT ORANGE (-1185 1600);
FORCEPROP 2 LASTPROP $XRERR UNIQUE?
J 0
(-1415 1600);
DISPLAY 0.638298 (-1415 1600);
PAINT MONO (-1415 1600);
DISPLAY INVISIBLE (-1415 1600);
WIRE 16 -1 (-1775 3825)(-2425 3825);
FORCEPROP 0 LAST SIG_NAME FAN_TACH0_CPU0_D2
J 0
(-2310 3835);
DISPLAY 0.617021 (-2310 3835);
PAINT ORANGE (-2310 3835);
FORCEPROP 2 LASTPROP $XRERR UNIQUE?
J 0
(-2550 3835);
DISPLAY 0.638298 (-2550 3835);
PAINT MONO (-2550 3835);
DISPLAY INVISIBLE (-2550 3835);
WIRE 16 -1 (-1875 675)(-2525 675);
FORCEPROP 0 LAST SIG_NAME FAN_TACH3_CPU1_D2
J 0
(-2435 685);
DISPLAY 0.617021 (-2435 685);
PAINT ORANGE (-2435 685);
FORCEPROP 2 LASTPROP $XRERR UNIQUE?
J 0
(-2675 685);
DISPLAY 0.638298 (-2675 685);
PAINT MONO (-2675 685);
DISPLAY INVISIBLE (-2675 685);
WIRE 16 -1 (-1925 1750)(-2575 1750);
FORCEPROP 0 LAST SIG_NAME FAN_TACH2_CPU1_D2
J 0
(-2460 1760);
DISPLAY 0.617021 (-2460 1760);
PAINT ORANGE (-2460 1760);
FORCEPROP 2 LASTPROP $XRERR UNIQUE?
J 0
(-2700 1760);
DISPLAY 0.638298 (-2700 1760);
PAINT MONO (-2700 1760);
DISPLAY INVISIBLE (-2700 1760);
WIRE 16 -1 (-2775 3725)(-2775 3825);
WIRE 16 -1 (-2775 3825)(-2625 3825);
WIRE 16 -1 (-2900 3825)(-2775 3825);
WIRE 16 -1 (-2900 3925)(-2900 3825);
WIRE 16 -1 (-3600 3825)(-2900 3825);
FORCEPROP 0 LAST SIG_NAME FAN_TACH0
J 0
(-3585 3835);
DISPLAY 0.617021 (-3585 3835);
PAINT ORANGE (-3585 3835);
WIRE 16 -1 (-2075 2775)(-2750 2775);
FORCEPROP 0 LAST SIG_NAME FAN_TACH1_CPU1_D2
J 0
(-2660 2785);
DISPLAY 0.617021 (-2660 2785);
PAINT ORANGE (-2660 2785);
FORCEPROP 2 LASTPROP $XRERR UNIQUE?
J 0
(-2900 2785);
DISPLAY 0.638298 (-2900 2785);
PAINT MONO (-2900 2785);
DISPLAY INVISIBLE (-2900 2785);
WIRE 16 -1 (-3225 2825)(-3225 2775);
WIRE 16 -1 (-2950 2775)(-3225 2775);
WIRE 16 -1 (-3300 2775)(-3225 2775);
WIRE 16 -1 (-3300 2725)(-3300 2775);
WIRE 16 -1 (-3575 2775)(-3300 2775);
FORCEPROP 0 LAST SIG_NAME FAN_TACH1
J 0
(-3560 2785);
DISPLAY 0.617021 (-3560 2785);
PAINT ORANGE (-3560 2785);
WIRE 16 -1 (-2925 1650)(-2925 1750);
WIRE 16 -1 (-2925 1750)(-2775 1750);
WIRE 16 -1 (-3050 1750)(-2925 1750);
WIRE 16 -1 (-3050 1850)(-3050 1750);
WIRE 16 -1 (-3550 1750)(-3050 1750);
FORCEPROP 0 LAST SIG_NAME FAN_TACH2
J 0
(-3535 1760);
DISPLAY 0.617021 (-3535 1760);
PAINT ORANGE (-3535 1760);
WIRE 16 -1 (-2725 675)(-2925 675);
WIRE 16 -1 (-2925 725)(-2925 675);
WIRE 16 -1 (-2925 675)(-3175 675);
WIRE 16 -1 (-3175 650)(-3175 675);
WIRE 16 -1 (-3175 675)(-3525 675);
FORCEPROP 0 LAST SIG_NAME FAN_TACH3
J 0
(-3510 685);
DISPLAY 0.617021 (-3510 685);
PAINT ORANGE (-3510 685);
WIRE 16 -1 (-5350 3850)(-4850 3850);
FORCEPROP 0 LAST SIG_NAME FAN_PWM_OUT_SYS0_R
J 0
(-5285 3860);
DISPLAY 0.617021 (-5285 3860);
PAINT ORANGE (-5285 3860);
WIRE 16 -1 (-5950 2700)(-5950 2575);
WIRE 16 -1 (-5950 2575)(-5350 2575);
FORCEPROP 0 LAST SIG_NAME FM_ENABLE_FAN_POWER
J 0
(-5885 2585);
DISPLAY 0.617021 (-5885 2585);
PAINT ORANGE (-5885 2585);
WIRE 16 -1 (-6100 2575)(-5950 2575);
WIRE 16 -1 (-5500 1100)(-4950 1100);
FORCEPROP 0 LAST SIG_NAME FAN_PWM_OUT_SYS1_R
J 0
(-5435 1110);
DISPLAY 0.617021 (-5435 1110);
PAINT ORANGE (-5435 1110);
WIRE 16 -1 (-5700 1100)(-6275 1100);
FORCEPROP 0 LAST SIG_NAME FAN_PWM_OUT_SYS1_BUF
J 0
(-6210 1110);
DISPLAY 0.617021 (-6210 1110);
PAINT ORANGE (-6210 1110);
FORCEPROP 2 LASTPROP $XRERR UNIQUE?
J 0
(-6450 1110);
DISPLAY 0.638298 (-6450 1110);
PAINT MONO (-6450 1110);
DISPLAY INVISIBLE (-6450 1110);
WIRE 16 -1 (-6200 3850)(-5550 3850);
FORCEPROP 0 LAST SIG_NAME FAN_PWM_OUT_SYS0_BUF
J 0
(-6085 3850);
DISPLAY 0.617021 (-6085 3850);
PAINT ORANGE (-6085 3850);
FORCEPROP 2 LASTPROP $XRERR UNIQUE?
J 0
(-6325 3850);
DISPLAY 0.638298 (-6325 3850);
PAINT MONO (-6325 3850);
DISPLAY INVISIBLE (-6325 3850);
WIRE 16 -1 (-6400 2625)(-7100 2625);
FORCEPROP 0 LAST SIG_NAME FM_CTNR_PS_ON
J 0
(-7060 2635);
DISPLAY 0.617021 (-7060 2635);
PAINT ORANGE (-7060 2635);
WIRE 16 -1 (-7100 2525)(-6400 2525);
FORCEPROP 0 LAST SIG_NAME FM_DISABLE_FAN_N
J 0
(-7085 2535);
DISPLAY 0.617021 (-7085 2535);
PAINT ORANGE (-7085 2535);
WIRE 16 -1 (-7200 3850)(-6450 3850);
FORCEPROP 0 LAST SIG_NAME FAN_PWM_OUT_SYS0
J 0
(-7175 3860);
DISPLAY 0.617021 (-7175 3860);
PAINT ORANGE (-7175 3860);
WIRE 16 -1 (-7325 1100)(-6525 1100);
FORCEPROP 0 LAST SIG_NAME FAN_PWM_OUT_SYS1
J 0
(-7350 1110);
DISPLAY 0.617021 (-7350 1110);
PAINT ORANGE (-7350 1110);
DOT 1 (-5950 2575);
DOT 1 (-3175 675);
DOT 1 (-2925 675);
DOT 1 (-3050 1750);
DOT 1 (-2925 1750);
DOT 1 (-2325 1125);
DOT 1 (-2100 1075);
DOT 1 (-2100 1425);
DOT 1 (-3300 2775);
DOT 1 (-3225 2775);
DOT 1 (-2900 3825);
DOT 1 (-2775 3825);
DOT 1 (-2175 3225);
DOT 1 (-1300 2075);
DOT 1 (-1375 2475);
DOT 1 (-1300 2475);
DOT 1 (-1950 3150);
DOT 1 (-1950 3500);
DOT 1 (-1500 4550);
DOT 1 (-1400 4550);
DOT 1 (-1125 4150);
FORCENOTE
ROOM=CPU_FANS
(-7925 325) 0;
DISPLAY LEFT (-7925 325);
DISPLAY 1.021277 (-7925 325);
PAINT PURPLE (-7925 325);
FORCENOTE
BOM_COST=SM_THERM
(-7925 225) 0;
DISPLAY LEFT (-7925 225);
DISPLAY 1.021277 (-7925 225);
PAINT PURPLE (-7925 225);
QUIT
